FILE_TYPE = MACRO_DRAWING;
SET COLOR_WIRE YELLOW;
SET COLOR_PROP ORANGE;
SET COLOR_DOT WHITE;
SET COLOR_ARC YELLOW;
SET COLOR_BODY GREEN;
SET COLOR_NOTE PURPLE;
SET PROP_DISPLAY VALUE;
SET PAGE_NUMBER P372;
FORCEADD ZENER_AC..1
R 1
(-8575 5525);
FORCEPROP 1 LAST LOCATION PD15
J 0
(-8525 5475);
DISPLAY 0.723404 (-8525 5475);
PAINT AQUA (-8525 5475);
FORCEPROP 0 LAST $SEC 1
R 1
J 0
(-8525 5625);
DISPLAY 0.680851 (-8525 5625);
PAINT MONO (-8525 5625);
DISPLAY INVISIBLE (-8525 5625);
FORCEPROP 0 LAST CDS_SEC 1
R 1
J 0
(-8525 5625);
DISPLAY 1.021277 (-8525 5625);
DISPLAY INVISIBLE (-8525 5625);
FORCEPROP 0 LASTPIN (-8575 5400) $PN A
R 1
J 2
(-8585 5390);
DISPLAY 0.680851 (-8585 5390);
PAINT MONO (-8585 5390);
FORCEPROP 0 LASTPIN (-8575 5650) $PN C
R 1
J 0
(-8585 5660);
DISPLAY 0.680851 (-8585 5660);
PAINT MONO (-8585 5660);
FORCEPROP 2 LAST VALUE 5.0SMDJ14A
J 0
(-8525 5525);
DISPLAY 0.723404 (-8525 5525);
PAINT SKYBLUE (-8525 5525);
FORCEPROP 2 LAST PART_TYPE SMLF
J 0
(-8525 5575);
DISPLAY 1.021277 (-8525 5575);
FORCEPROP 1 LAST MATERIAL IC
J 0
(-8525 5375);
DISPLAY 0.723404 (-8525 5375);
PAINT SKYBLUE (-8525 5375);
FORCEPROP 1 LAST NEEDS_NO_SIZE TRUE
R 1
J 0
(-8575 5525);
DISPLAY 0.723404 (-8575 5525);
PAINT GREEN (-8575 5525);
DISPLAY INVISIBLE (-8575 5525);
FORCEPROP 1 LAST CDS_LMAN_SYM_OUTLINE -75,50,75,-50
R 1
J 0
(-8575 5525);
DISPLAY 0.468085 (-8575 5525);
PAINT GREEN (-8575 5525);
DISPLAY INVISIBLE (-8575 5525);
FORCEPROP 2 LAST CDS_LIB pure_quanta
J 0
(-8575 5525);
DISPLAY INVISIBLE (-8575 5525);
FORCEPROP 1 LAST PATH I1
R 1
J 0
(-8575 5525);
DISPLAY 0.723404 (-8575 5525);
PAINT GREEN (-8575 5525);
DISPLAY INVISIBLE (-8575 5525);
FORCEPROP 1 LAST PART_NUMBER BC0MDJ14000
J 0
(-8525 5425);
DISPLAY 0.723404 (-8525 5425);
PAINT WHITE (-8525 5425);
DISPLAY INVISIBLE (-8525 5425);
FORCEADD Q_RES..2
(-7950 600);
FORCEPROP 1 LAST LOCATION R3907
J 0
(-7905 725);
DISPLAY 0.723404 (-7905 725);
PAINT AQUA (-7905 725);
FORCEPROP 0 LAST $SEC 1
J 0
(-7900 775);
DISPLAY INVISIBLE (-7900 775);
FORCEPROP 0 LAST CDS_SEC 1
J 0
(-7900 775);
DISPLAY INVISIBLE (-7900 775);
FORCEPROP 1 LASTPIN (-7950 700) $PN 1
J 0
(-7945 662);
DISPLAY 0.787234 (-7945 662);
PAINT MONO (-7945 662);
DISPLAY INVISIBLE (-7945 662);
FORCEPROP 1 LASTPIN (-7950 500) $PN 2
J 0
(-7945 510);
DISPLAY 0.787234 (-7945 510);
PAINT MONO (-7945 510);
DISPLAY INVISIBLE (-7945 510);
FORCEPROP 1 LAST VALUE 33K
J 0
(-7905 675);
DISPLAY 0.723404 (-7905 675);
PAINT SKYBLUE (-7905 675);
FORCEPROP 1 LAST TOLERANCE 1%
J 0
(-7905 625);
DISPLAY 0.723404 (-7905 625);
PAINT SKYBLUE (-7905 625);
FORCEPROP 1 LAST WATTAGE 1/16W
J 0
(-7910 575);
DISPLAY 0.723404 (-7910 575);
PAINT SKYBLUE (-7910 575);
FORCEPROP 1 LAST PACK_TYPE 0402LF
J 0
(-7900 475);
DISPLAY 0.723404 (-7900 475);
PAINT SKYBLUE (-7900 475);
FORCEPROP 1 LAST MATERIAL CHIP
J 0
(-7910 525);
DISPLAY 0.723404 (-7910 525);
PAINT SKYBLUE (-7910 525);
DISPLAY INVISIBLE (-7910 525);
FORCEPROP 2 LAST CDS_LIB pure_quanta
J 0
(-7950 600);
DISPLAY INVISIBLE (-7950 600);
FORCEPROP 1 LAST PATH I10
J 0
(-7900 775);
DISPLAY 0.978723 (-7900 775);
PAINT WHITE (-7900 775);
DISPLAY INVISIBLE (-7900 775);
FORCEPROP 1 LAST PART_NUMBER CS33302FB00
J 0
(-7900 525);
DISPLAY 0.723404 (-7900 525);
PAINT WHITE (-7900 525);
DISPLAY INVISIBLE (-7900 525);
FORCEADD GND..1
(-6925 3350);
FORCEPROP 3 LASTPIN (-6925 3400) SIG_NAME GND\g
J 0
(-6915 3410);
DISPLAY 0.659574 (-6915 3410);
PAINT MONO (-6915 3410);
DISPLAY INVISIBLE (-6915 3410);
FORCEPROP 1 LAST SIZE 1B
J 0
(-6850 3300);
DISPLAY 0.872340 (-6850 3300);
PAINT AQUA (-6850 3300);
DISPLAY INVISIBLE (-6850 3300);
FORCEPROP 2 LAST CDS_LIB pure_quanta_power
J 0
(-6925 3350);
DISPLAY INVISIBLE (-6925 3350);
FORCEPROP 1 LAST HDL_POWER GND
J 0
(-6925 3500);
DISPLAY 1.170213 (-6925 3500);
PAINT GREEN (-6925 3500);
DISPLAY INVISIBLE (-6925 3500);
FORCEPROP 1 LAST PATH I100
J 0
(-6850 3350);
DISPLAY 0.872340 (-6850 3350);
PAINT AQUA (-6850 3350);
DISPLAY INVISIBLE (-6850 3350);
FORCEADD OFFPAGE..4
(-7025 3600);
FORCEPROP 2 LAST $XR1 268 
J 0
(-6719 3600);
DISPLAY 0.638298 (-6719 3600);
PAINT MONO (-6719 3600);
FORCEPROP 2 LAST $XR0 151 
J 0
(-6839 3600);
DISPLAY 0.638298 (-6839 3600);
PAINT MONO (-6839 3600);
FORCEPROP 2 LAST CDS_LIB standard
J 2
(-7025 3600);
DISPLAY INVISIBLE (-7025 3600);
FORCEPROP 1 LAST OFFPAGE TRUE
J 0
(-6700 3475);
DISPLAY 0.872340 (-6700 3475);
PAINT GREEN (-6700 3475);
DISPLAY INVISIBLE (-6700 3475);
FORCEPROP 1 LAST COMMENT_BODY TRUE
J 0
(-7050 3500);
DISPLAY 0.872340 (-7050 3500);
PAINT GREEN (-7050 3500);
DISPLAY INVISIBLE (-7050 3500);
FORCEPROP 2 LAST PATH I101
J 0
(-6825 3675);
DISPLAY 0.680851 (-6825 3675);
DISPLAY INVISIBLE (-6825 3675);
FORCEADD OFFPAGE..3
(-7025 3550);
FORCEPROP 2 LAST $XR1 268 
J 0
(-6691 3550);
DISPLAY 0.638298 (-6691 3550);
PAINT MONO (-6691 3550);
FORCEPROP 2 LAST $XR0 151 
J 0
(-6811 3550);
DISPLAY 0.638298 (-6811 3550);
PAINT MONO (-6811 3550);
FORCEPROP 2 LAST CDS_LIB standard
J 2
(-7025 3550);
DISPLAY INVISIBLE (-7025 3550);
FORCEPROP 1 LAST OFFPAGE TRUE
J 0
(-6700 3425);
DISPLAY 0.872340 (-6700 3425);
PAINT GREEN (-6700 3425);
DISPLAY INVISIBLE (-6700 3425);
FORCEPROP 1 LAST COMMENT_BODY TRUE
J 0
(-7075 3450);
DISPLAY 0.872340 (-7075 3450);
PAINT GREEN (-7075 3450);
DISPLAY INVISIBLE (-7075 3450);
FORCEPROP 2 LAST PATH I102
J 0
(-6675 3600);
DISPLAY 0.680851 (-6675 3600);
DISPLAY INVISIBLE (-6675 3600);
FORCEADD CONN3_210HP1030BR1..1
R 2
(-7850 3550);
PAINT AQUA (-7850 3550);
FORCEPROP 1 LAST LOCATION JP10
J 2
(-7925 3525);
DISPLAY 0.723404 (-7925 3525);
PAINT AQUA (-7925 3525);
FORCEPROP 0 LAST $SEC 1
J 0
(-7900 3675);
DISPLAY 0.680851 (-7900 3675);
PAINT MONO (-7900 3675);
DISPLAY INVISIBLE (-7900 3675);
FORCEPROP 0 LAST CDS_SEC 1
J 0
(-7900 3675);
DISPLAY 1.021277 (-7900 3675);
DISPLAY INVISIBLE (-7900 3675);
FORCEPROP 0 LASTPIN (-7650 3600) $PN 1
J 0
(-7640 3610);
DISPLAY 0.680851 (-7640 3610);
PAINT MONO (-7640 3610);
FORCEPROP 0 LASTPIN (-7650 3550) $PN 2
J 0
(-7640 3560);
DISPLAY 0.680851 (-7640 3560);
PAINT MONO (-7640 3560);
FORCEPROP 0 LASTPIN (-7650 3500) $PN 3
J 0
(-7640 3510);
DISPLAY 0.680851 (-7640 3510);
PAINT MONO (-7640 3510);
FORCEPROP 1 LAST MATERIAL IO
J 2
(-7925 3424);
DISPLAY 0.723404 (-7925 3424);
PAINT SKYBLUE (-7925 3424);
FORCEPROP 2 LAST PART_TYPE THLF
J 2
(-7900 3575);
DISPLAY 1.021277 (-7900 3575);
FORCEPROP 2 LAST VALUE CONN3_210-HP1-030BR1
J 2
(-7900 3625);
DISPLAY 0.723404 (-7900 3625);
PAINT AQUA (-7900 3625);
FORCEPROP 2 LAST CDS_LIB pure_quanta
J 2
(-7850 3550);
DISPLAY INVISIBLE (-7850 3550);
FORCEPROP 1 LAST CDS_LMAN_SYM_OUTLINE -50,100,50,-100
J 2
(-7850 3550);
DISPLAY 0.468085 (-7850 3550);
PAINT GREEN (-7850 3550);
DISPLAY INVISIBLE (-7850 3550);
FORCEPROP 1 LAST NEEDS_NO_SIZE TRUE
J 2
(-7850 3550);
DISPLAY 0.723404 (-7850 3550);
PAINT GREEN (-7850 3550);
DISPLAY INVISIBLE (-7850 3550);
FORCEPROP 1 LAST PATH I103
J 2
(-7850 3550);
DISPLAY 0.723404 (-7850 3550);
PAINT GREEN (-7850 3550);
DISPLAY INVISIBLE (-7850 3550);
FORCEPROP 1 LAST PART_NUMBER DFHD03MS213
J 2
(-7925 3475);
DISPLAY 0.723404 (-7925 3475);
PAINT WHITE (-7925 3475);
DISPLAY INVISIBLE (-7925 3475);
FORCEADD Q_RES..2
(-650 2000);
FORCEPROP 1 LAST LOCATION R8125
J 0
(-605 2125);
DISPLAY 0.978723 (-605 2125);
FORCEPROP 0 LAST $SEC 1
J 0
(-600 2175);
DISPLAY 0.680851 (-600 2175);
PAINT MONO (-600 2175);
DISPLAY INVISIBLE (-600 2175);
FORCEPROP 0 LAST CDS_SEC 1
J 0
(-600 2175);
DISPLAY 0.680851 (-600 2175);
DISPLAY INVISIBLE (-600 2175);
FORCEPROP 1 LASTPIN (-650 2100) $PN 1
J 0
(-645 2062);
DISPLAY 0.787234 (-645 2062);
PAINT MONO (-645 2062);
FORCEPROP 1 LASTPIN (-650 1900) $PN 2
J 0
(-645 1910);
DISPLAY 0.787234 (-645 1910);
PAINT MONO (-645 1910);
FORCEPROP 1 LAST MATERIAL CHIP
J 0
(-610 1925);
DISPLAY 0.723404 (-610 1925);
FORCEPROP 1 LAST PACK_TYPE 0402LF
J 0
(-600 1875);
DISPLAY 0.723404 (-600 1875);
FORCEPROP 1 LAST WATTAGE 1/16W
J 0
(-610 1975);
DISPLAY 0.723404 (-610 1975);
FORCEPROP 1 LAST TOLERANCE 1%
J 0
(-605 2025);
DISPLAY 0.723404 (-605 2025);
FORCEPROP 1 LAST VALUE 1K
J 0
(-605 2075);
DISPLAY 0.723404 (-605 2075);
FORCEPROP 2 LAST CDS_LIB pure_quanta
J 0
(-650 2000);
DISPLAY INVISIBLE (-650 2000);
FORCEPROP 1 LAST PATH I104
J 0
(-600 2175);
DISPLAY 0.978723 (-600 2175);
PAINT WHITE (-600 2175);
DISPLAY INVISIBLE (-600 2175);
FORCEPROP 1 LAST PART_NUMBER CS21002FB06
J 0
(-610 1875);
DISPLAY 0.723404 (-610 1875);
PAINT WHITE (-610 1875);
DISPLAY INVISIBLE (-610 1875);
FORCEADD MOSFET_NCH_GDS_ESD_PROTECTED..1
(-7450 775);
FORCEPROP 1 LAST LOCATION U290
J 0
(-7308 739);
DISPLAY 0.574468 (-7308 739);
PAINT GREEN (-7308 739);
FORCEPROP 0 LAST $SEC 1
J 0
(-7300 875);
DISPLAY 0.680851 (-7300 875);
PAINT MONO (-7300 875);
DISPLAY INVISIBLE (-7300 875);
FORCEPROP 0 LAST CDS_SEC 1
J 0
(-7300 875);
DISPLAY 1.021277 (-7300 875);
DISPLAY INVISIBLE (-7300 875);
FORCEPROP 0 LASTPIN (-7425 975) $PN D
R 1
J 0
(-7435 985);
DISPLAY 0.680851 (-7435 985);
PAINT MONO (-7435 985);
FORCEPROP 0 LASTPIN (-7625 775) $PN G
J 2
(-7635 785);
DISPLAY 0.680851 (-7635 785);
PAINT MONO (-7635 785);
FORCEPROP 0 LASTPIN (-7425 575) $PN S
R 1
J 2
(-7435 565);
DISPLAY 0.680851 (-7435 565);
PAINT MONO (-7435 565);
FORCEPROP 2 LAST PART_TYPE SMLF
J 0
(-7300 825);
DISPLAY 0.808511 (-7300 825);
FORCEPROP 1 LAST MATERIAL IC
J 0
(-7308 630);
DISPLAY 0.574468 (-7308 630);
PAINT GREEN (-7308 630);
FORCEPROP 2 LAST VALUE 2N7002K
J 0
(-7300 775);
DISPLAY 0.808511 (-7300 775);
FORCEPROP 1 LAST CDS_LMAN_SYM_OUTLINE -125,150,125,-150
J 0
(-7450 775);
DISPLAY 0.468085 (-7450 775);
PAINT GREEN (-7450 775);
DISPLAY INVISIBLE (-7450 775);
FORCEPROP 2 LAST CDS_LIB pure_quanta
J 0
(-7450 775);
DISPLAY INVISIBLE (-7450 775);
FORCEPROP 1 LAST NEEDS_NO_SIZE TRUE
J 0
(-7325 665);
DISPLAY 0.723404 (-7325 665);
PAINT GREEN (-7325 665);
DISPLAY INVISIBLE (-7325 665);
FORCEPROP 1 LAST PATH I11
J 0
(-7325 625);
DISPLAY 0.723404 (-7325 625);
PAINT GREEN (-7325 625);
DISPLAY INVISIBLE (-7325 625);
FORCEPROP 1 LAST PART_NUMBER BAM70020002
J 0
(-7308 687);
DISPLAY 0.574468 (-7308 687);
PAINT GREEN (-7308 687);
DISPLAY INVISIBLE (-7308 687);
FORCEADD GND..1
(-7425 325);
FORCEPROP 3 LASTPIN (-7425 375) SIG_NAME GND\g
J 0
(-7415 385);
DISPLAY 0.659574 (-7415 385);
PAINT MONO (-7415 385);
DISPLAY INVISIBLE (-7415 385);
FORCEPROP 2 LAST ROOM VR_DDR1_POWER_STAGE
J 0
(-7650 400);
FORCEPROP 1 LAST SIZE 1B
J 0
(-7350 275);
DISPLAY 0.872340 (-7350 275);
PAINT AQUA (-7350 275);
DISPLAY INVISIBLE (-7350 275);
FORCEPROP 2 LAST CDS_LIB pure_quanta_power
J 0
(-7425 325);
DISPLAY INVISIBLE (-7425 325);
FORCEPROP 1 LAST HDL_POWER GND
J 0
(-7425 475);
DISPLAY 1.170213 (-7425 475);
PAINT GREEN (-7425 475);
DISPLAY INVISIBLE (-7425 475);
FORCEPROP 1 LAST PATH I12
J 0
(-7350 325);
DISPLAY 0.872340 (-7350 325);
PAINT AQUA (-7350 325);
DISPLAY INVISIBLE (-7350 325);
FORCEADD Q_RES..2
(-6525 900);
FORCEPROP 1 LAST LOCATION R2585
J 0
(-6480 1025);
DISPLAY 0.723404 (-6480 1025);
PAINT AQUA (-6480 1025);
FORCEPROP 0 LAST $SEC 1
J 0
(-6475 1075);
DISPLAY INVISIBLE (-6475 1075);
FORCEPROP 0 LAST CDS_SEC 1
J 0
(-6475 1075);
DISPLAY INVISIBLE (-6475 1075);
FORCEPROP 1 LASTPIN (-6525 1000) $PN 1
J 0
(-6520 962);
DISPLAY 0.787234 (-6520 962);
PAINT MONO (-6520 962);
DISPLAY INVISIBLE (-6520 962);
FORCEPROP 1 LASTPIN (-6525 800) $PN 2
J 0
(-6520 810);
DISPLAY 0.787234 (-6520 810);
PAINT MONO (-6520 810);
DISPLAY INVISIBLE (-6520 810);
FORCEPROP 1 LAST WATTAGE 1/16W
J 0
(-6485 875);
DISPLAY 0.723404 (-6485 875);
PAINT SKYBLUE (-6485 875);
FORCEPROP 1 LAST PACK_TYPE 0402LF
J 0
(-6485 725);
DISPLAY 0.723404 (-6485 725);
PAINT SKYBLUE (-6485 725);
FORCEPROP 1 LAST TOLERANCE 1%
J 0
(-6480 925);
DISPLAY 0.723404 (-6480 925);
PAINT SKYBLUE (-6480 925);
FORCEPROP 1 LAST VALUE 31.6K
J 0
(-6480 975);
DISPLAY 0.723404 (-6480 975);
PAINT SKYBLUE (-6480 975);
FORCEPROP 1 LAST MATERIAL CHIP
J 0
(-6485 825);
DISPLAY 0.723404 (-6485 825);
PAINT SKYBLUE (-6485 825);
FORCEPROP 2 LAST CDS_LIB pure_quanta
J 0
(-6525 900);
DISPLAY INVISIBLE (-6525 900);
FORCEPROP 1 LAST PATH I13
J 0
(-6475 1075);
DISPLAY 0.978723 (-6475 1075);
PAINT WHITE (-6475 1075);
DISPLAY INVISIBLE (-6475 1075);
FORCEPROP 1 LAST PART_NUMBER CS33162FB02
J 0
(-6485 775);
DISPLAY 0.723404 (-6485 775);
PAINT WHITE (-6485 775);
DISPLAY INVISIBLE (-6485 775);
FORCEADD GND..1
(-6525 650);
FORCEPROP 3 LASTPIN (-6525 700) SIG_NAME GND\g
J 0
(-6515 710);
DISPLAY 0.659574 (-6515 710);
PAINT MONO (-6515 710);
DISPLAY INVISIBLE (-6515 710);
FORCEPROP 2 LAST ROOM VR_DDR1_POWER_STAGE
J 0
(-6750 725);
FORCEPROP 2 LAST CDS_LIB pure_quanta_power
J 0
(-6525 650);
DISPLAY INVISIBLE (-6525 650);
FORCEPROP 1 LAST SIZE 1B
J 0
(-6450 600);
DISPLAY 0.872340 (-6450 600);
PAINT AQUA (-6450 600);
DISPLAY INVISIBLE (-6450 600);
FORCEPROP 1 LAST HDL_POWER GND
J 0
(-6525 800);
DISPLAY 1.170213 (-6525 800);
PAINT GREEN (-6525 800);
DISPLAY INVISIBLE (-6525 800);
FORCEPROP 1 LAST PATH I14
J 0
(-6450 650);
DISPLAY 0.872340 (-6450 650);
PAINT AQUA (-6450 650);
DISPLAY INVISIBLE (-6450 650);
FORCEADD Q_RES..2
(-8000 1100);
FORCEPROP 1 LAST LOCATION R3923
J 0
(-7955 1225);
DISPLAY 0.723404 (-7955 1225);
PAINT AQUA (-7955 1225);
FORCEPROP 0 LAST $SEC 1
J 0
(-7950 1275);
DISPLAY 0.680851 (-7950 1275);
PAINT MONO (-7950 1275);
DISPLAY INVISIBLE (-7950 1275);
FORCEPROP 0 LAST CDS_SEC 1
J 0
(-7950 1275);
DISPLAY 1.021277 (-7950 1275);
DISPLAY INVISIBLE (-7950 1275);
FORCEPROP 1 LASTPIN (-8000 1200) $PN 1
J 0
(-7995 1162);
DISPLAY 0.787234 (-7995 1162);
PAINT MONO (-7995 1162);
FORCEPROP 1 LASTPIN (-8000 1000) $PN 2
J 0
(-7995 1010);
DISPLAY 0.787234 (-7995 1010);
PAINT MONO (-7995 1010);
FORCEPROP 1 LAST TOLERANCE 1%
J 0
(-7955 1125);
DISPLAY 0.723404 (-7955 1125);
PAINT SKYBLUE (-7955 1125);
FORCEPROP 1 LAST WATTAGE 1/16W
J 0
(-7960 1075);
DISPLAY 0.723404 (-7960 1075);
PAINT SKYBLUE (-7960 1075);
FORCEPROP 1 LAST VALUE 63.4K
J 0
(-7955 1175);
DISPLAY 0.723404 (-7955 1175);
PAINT SKYBLUE (-7955 1175);
FORCEPROP 1 LAST PACK_TYPE 0402LF
J 0
(-7950 975);
DISPLAY 0.723404 (-7950 975);
PAINT SKYBLUE (-7950 975);
FORCEPROP 2 LAST CDS_LIB pure_quanta
J 0
(-8000 1100);
DISPLAY INVISIBLE (-8000 1100);
FORCEPROP 1 LAST MATERIAL CHIP
J 0
(-7960 1025);
DISPLAY 0.723404 (-7960 1025);
PAINT SKYBLUE (-7960 1025);
DISPLAY INVISIBLE (-7960 1025);
FORCEPROP 1 LAST PATH I16
J 0
(-7950 1275);
DISPLAY 0.978723 (-7950 1275);
PAINT WHITE (-7950 1275);
DISPLAY INVISIBLE (-7950 1275);
FORCEPROP 1 LAST PART_NUMBER CS36342FB04
J 0
(-7950 1025);
DISPLAY 0.723404 (-7950 1025);
PAINT WHITE (-7950 1025);
DISPLAY INVISIBLE (-7950 1025);
FORCEADD GND..1
(-8225 1750);
FORCEPROP 3 LASTPIN (-8225 1800) SIG_NAME GND\g
J 0
(-8215 1810);
DISPLAY 0.659574 (-8215 1810);
PAINT MONO (-8215 1810);
DISPLAY INVISIBLE (-8215 1810);
FORCEPROP 2 LAST ROOM VR_DDR1_POWER_STAGE
J 0
(-8450 1825);
FORCEPROP 1 LAST SIZE 1B
J 0
(-8150 1700);
DISPLAY 0.872340 (-8150 1700);
PAINT AQUA (-8150 1700);
DISPLAY INVISIBLE (-8150 1700);
FORCEPROP 2 LAST CDS_LIB pure_quanta_power
J 0
(-8225 1750);
DISPLAY INVISIBLE (-8225 1750);
FORCEPROP 1 LAST HDL_POWER GND
J 0
(-8225 1900);
DISPLAY 1.170213 (-8225 1900);
PAINT GREEN (-8225 1900);
DISPLAY INVISIBLE (-8225 1900);
FORCEPROP 1 LAST PATH I17
J 0
(-8150 1750);
DISPLAY 0.872340 (-8150 1750);
PAINT AQUA (-8150 1750);
DISPLAY INVISIBLE (-8150 1750);
FORCEADD CONN3_210HP1030BR1..1
(-7975 1950);
PAINT AQUA (-7975 1950);
FORCEPROP 1 LAST LOCATION JP4003
J 0
(-8025 2175);
DISPLAY 0.723404 (-8025 2175);
PAINT AQUA (-8025 2175);
FORCEPROP 0 LAST $SEC 1
J 0
(-8025 2325);
DISPLAY 0.680851 (-8025 2325);
PAINT MONO (-8025 2325);
DISPLAY INVISIBLE (-8025 2325);
FORCEPROP 0 LAST CDS_SEC 1
J 0
(-8025 2325);
DISPLAY 1.021277 (-8025 2325);
DISPLAY INVISIBLE (-8025 2325);
FORCEPROP 0 LASTPIN (-8175 2000) $PN 1
J 2
(-8185 2010);
DISPLAY 0.680851 (-8185 2010);
PAINT MONO (-8185 2010);
FORCEPROP 0 LASTPIN (-8175 1950) $PN 2
J 2
(-8185 1960);
DISPLAY 0.680851 (-8185 1960);
PAINT MONO (-8185 1960);
FORCEPROP 0 LASTPIN (-8175 1900) $PN 3
J 2
(-8185 1910);
DISPLAY 0.680851 (-8185 1910);
PAINT MONO (-8185 1910);
FORCEPROP 1 LAST MATERIAL IO
J 0
(-8038 2074);
DISPLAY 0.723404 (-8038 2074);
PAINT SKYBLUE (-8038 2074);
FORCEPROP 2 LAST PART_TYPE THLF
J 0
(-8025 2275);
DISPLAY 1.021277 (-8025 2275);
FORCEPROP 2 LAST VALUE CONN3_210-HP1-030BR1
J 0
(-8025 2225);
DISPLAY 0.723404 (-8025 2225);
PAINT AQUA (-8025 2225);
FORCEPROP 1 LAST NEEDS_NO_SIZE TRUE
J 0
(-7975 1950);
DISPLAY 0.723404 (-7975 1950);
PAINT GREEN (-7975 1950);
DISPLAY INVISIBLE (-7975 1950);
FORCEPROP 1 LAST CDS_LMAN_SYM_OUTLINE -50,100,50,-100
J 0
(-7975 1950);
DISPLAY 0.468085 (-7975 1950);
PAINT GREEN (-7975 1950);
DISPLAY INVISIBLE (-7975 1950);
FORCEPROP 2 LAST CDS_LIB pure_quanta
J 0
(-7975 1950);
DISPLAY INVISIBLE (-7975 1950);
FORCEPROP 1 LAST PATH I18
J 0
(-7975 1950);
DISPLAY 0.723404 (-7975 1950);
PAINT GREEN (-7975 1950);
DISPLAY INVISIBLE (-7975 1950);
FORCEPROP 1 LAST PART_NUMBER DFHD03MS213
J 0
(-8025 2125);
DISPLAY 0.723404 (-8025 2125);
PAINT WHITE (-8025 2125);
DISPLAY INVISIBLE (-8025 2125);
FORCEADD Q_RES..1
(-6825 1500);
FORCEPROP 1 LAST LOCATION R4901
J 0
(-7075 1525);
DISPLAY 0.723404 (-7075 1525);
PAINT AQUA (-7075 1525);
FORCEPROP 0 LAST $SEC 1
J 0
(-6725 1575);
DISPLAY 0.680851 (-6725 1575);
PAINT MONO (-6725 1575);
DISPLAY INVISIBLE (-6725 1575);
FORCEPROP 0 LAST CDS_SEC 1
J 0
(-6725 1575);
DISPLAY 1.021277 (-6725 1575);
DISPLAY INVISIBLE (-6725 1575);
FORCEPROP 1 LASTPIN (-6925 1500) $PN 1
J 0
(-6913 1512);
DISPLAY 0.787234 (-6913 1512);
PAINT MONO (-6913 1512);
FORCEPROP 1 LASTPIN (-6725 1500) $PN 2
J 0
(-6763 1512);
DISPLAY 0.787234 (-6763 1512);
PAINT MONO (-6763 1512);
FORCEPROP 1 LAST VALUE 82K
J 2
(-6775 1525);
DISPLAY 0.723404 (-6775 1525);
PAINT SKYBLUE (-6775 1525);
FORCEPROP 1 LAST WATTAGE 1/16W
J 2
(-6925 1425);
DISPLAY 0.723404 (-6925 1425);
PAINT SKYBLUE (-6925 1425);
FORCEPROP 1 LAST TOLERANCE 1%
J 0
(-6725 1525);
DISPLAY 0.723404 (-6725 1525);
PAINT SKYBLUE (-6725 1525);
FORCEPROP 1 LAST MATERIAL CHIP
J 0
(-6900 1425);
DISPLAY 0.723404 (-6900 1425);
PAINT SKYBLUE (-6900 1425);
FORCEPROP 1 LAST PACK_TYPE 0402LF
J 0
(-6725 1425);
DISPLAY 0.723404 (-6725 1425);
PAINT SKYBLUE (-6725 1425);
FORCEPROP 2 LAST CDS_LIB pure_quanta
J 0
(-6825 1500);
DISPLAY INVISIBLE (-6825 1500);
FORCEPROP 1 LAST PATH I19
J 0
(-6875 1650);
DISPLAY 0.978723 (-6875 1650);
PAINT WHITE (-6875 1650);
DISPLAY INVISIBLE (-6875 1650);
FORCEPROP 1 LAST PART_NUMBER CS38202FB01
J 0
(-6975 1375);
DISPLAY 0.723404 (-6975 1375);
PAINT WHITE (-6975 1375);
DISPLAY INVISIBLE (-6975 1375);
FORCEADD OFFPAGE..5
(-8850 5725);
FORCEPROP 2 LAST $XR0 269 
J 0
(-9135 5725);
DISPLAY 0.638298 (-9135 5725);
PAINT MONO (-9135 5725);
FORCEPROP 2 LAST CDS_LIB standard
J 0
(-8850 5725);
DISPLAY INVISIBLE (-8850 5725);
FORCEPROP 1 LAST OFFPAGE TRUE
J 0
(-8525 5600);
DISPLAY 0.872340 (-8525 5600);
PAINT AQUA (-8525 5600);
DISPLAY INVISIBLE (-8525 5600);
FORCEPROP 1 LAST COMMENT_BODY TRUE
J 0
(-8750 5650);
DISPLAY 1.170213 (-8750 5650);
PAINT GREEN (-8750 5650);
DISPLAY INVISIBLE (-8750 5650);
FORCEPROP 2 LAST PATH I2
J 0
(-8800 5800);
DISPLAY 0.680851 (-8800 5800);
DISPLAY INVISIBLE (-8800 5800);
FORCEADD OFFPAGE..4
(-6575 1725);
FORCEPROP 2 LAST $XR0 269 
J 0
(-6389 1725);
DISPLAY 0.638298 (-6389 1725);
PAINT MONO (-6389 1725);
FORCEPROP 2 LAST CDS_LIB standard
J 2
(-6575 1725);
DISPLAY INVISIBLE (-6575 1725);
FORCEPROP 1 LAST OFFPAGE TRUE
J 0
(-6250 1600);
DISPLAY 0.872340 (-6250 1600);
PAINT GREEN (-6250 1600);
DISPLAY INVISIBLE (-6250 1600);
FORCEPROP 1 LAST COMMENT_BODY TRUE
J 0
(-6600 1625);
DISPLAY 0.872340 (-6600 1625);
PAINT GREEN (-6600 1625);
DISPLAY INVISIBLE (-6600 1625);
FORCEPROP 2 LAST PATH I20
J 0
(-6375 1775);
DISPLAY 0.680851 (-6375 1775);
DISPLAY INVISIBLE (-6375 1775);
FORCEADD Q_CAP..1
(-5900 1000);
FORCEPROP 1 LAST LOCATION C2179
J 0
(-5850 1125);
DISPLAY 0.723404 (-5850 1125);
PAINT AQUA (-5850 1125);
FORCEPROP 0 LAST SEC 1
J 0
(-5850 1150);
DISPLAY INVISIBLE (-5850 1150);
FORCEPROP 1 LASTPIN (-5900 1100) $PN 1
J 0
(-5890 1080);
DISPLAY 0.787234 (-5890 1080);
PAINT MONO (-5890 1080);
FORCEPROP 1 LASTPIN (-5900 900) $PN 2
J 0
(-5890 880);
DISPLAY 0.787234 (-5890 880);
PAINT MONO (-5890 880);
FORCEPROP 1 LAST PACK_TYPE C0402
J 0
(-5850 825);
DISPLAY 0.723404 (-5850 825);
PAINT SKYBLUE (-5850 825);
FORCEPROP 1 LAST VOLTAGE 50V
J 0
(-5850 1025);
DISPLAY 0.723404 (-5850 1025);
PAINT SKYBLUE (-5850 1025);
FORCEPROP 1 LAST MATERIAL X7R
J 0
(-5850 925);
DISPLAY 0.723404 (-5850 925);
PAINT SKYBLUE (-5850 925);
FORCEPROP 1 LAST VALUE 100NF
J 0
(-5850 1075);
DISPLAY 0.723404 (-5850 1075);
PAINT SKYBLUE (-5850 1075);
FORCEPROP 1 LAST TOLERANCE 10%
J 0
(-5850 975);
DISPLAY 0.723404 (-5850 975);
PAINT SKYBLUE (-5850 975);
FORCEPROP 2 LAST SEC_TYPE C0402
J 0
(-5850 1200);
DISPLAY 0.680851 (-5850 1200);
DISPLAY INVISIBLE (-5850 1200);
FORCEPROP 2 LAST CDS_LIB pure_quanta
J 0
(-5900 1000);
DISPLAY INVISIBLE (-5900 1000);
FORCEPROP 1 LAST PATH I22
J 0
(-5850 1150);
DISPLAY 0.978723 (-5850 1150);
PAINT WHITE (-5850 1150);
DISPLAY INVISIBLE (-5850 1150);
FORCEPROP 1 LAST PART_NUMBER CH4106K1B01
J 0
(-5850 875);
DISPLAY 0.723404 (-5850 875);
PAINT WHITE (-5850 875);
DISPLAY INVISIBLE (-5850 875);
FORCEADD OFFPAGE..5
R 2
(-5750 1500);
FORCEPROP 2 LAST $XR1 268 
J 0
(-5441 1500);
DISPLAY 0.638298 (-5441 1500);
PAINT MONO (-5441 1500);
FORCEPROP 2 LAST $XR0 263 
J 0
(-5561 1500);
DISPLAY 0.638298 (-5561 1500);
PAINT MONO (-5561 1500);
FORCEPROP 2 LAST CDS_LIB standard
J 2
(-5750 1500);
DISPLAY INVISIBLE (-5750 1500);
FORCEPROP 1 LAST OFFPAGE TRUE
J 2
(-6075 1375);
DISPLAY 0.872340 (-6075 1375);
PAINT AQUA (-6075 1375);
DISPLAY INVISIBLE (-6075 1375);
FORCEPROP 1 LAST COMMENT_BODY TRUE
J 2
(-5850 1425);
DISPLAY 1.170213 (-5850 1425);
PAINT GREEN (-5850 1425);
DISPLAY INVISIBLE (-5850 1425);
FORCEPROP 2 LAST PATH I23
J 0
(-5550 1550);
DISPLAY 0.680851 (-5550 1550);
DISPLAY INVISIBLE (-5550 1550);
FORCEADD UNIVERSAL_GND..1
(-5900 650);
FORCEPROP 3 LASTPIN (-5900 700) SIG_NAME GND\g
J 0
(-5890 710);
DISPLAY 0.659574 (-5890 710);
PAINT MONO (-5890 710);
DISPLAY INVISIBLE (-5890 710);
FORCEPROP 2 LAST CDS_LIB pure_quanta_power
J 0
(-5900 650);
DISPLAY INVISIBLE (-5900 650);
FORCEPROP 1 LAST HDL_POWER GND
J 1
(-5875 575);
DISPLAY 0.872340 (-5875 575);
PAINT GREEN (-5875 575);
DISPLAY INVISIBLE (-5875 575);
FORCEPROP 1 LAST PATH I24
J 0
(-5825 650);
DISPLAY 0.872340 (-5825 650);
PAINT AQUA (-5825 650);
DISPLAY INVISIBLE (-5825 650);
FORCEADD GND..1
(-8725 4650);
FORCEPROP 3 LASTPIN (-8725 4700) SIG_NAME GND\g
J 0
(-8715 4710);
DISPLAY 0.659574 (-8715 4710);
PAINT MONO (-8715 4710);
DISPLAY INVISIBLE (-8715 4710);
FORCEPROP 2 LAST CDS_LIB pure_quanta_power
J 0
(-8725 4650);
DISPLAY INVISIBLE (-8725 4650);
FORCEPROP 1 LAST SIZE 1B
J 0
(-8650 4600);
DISPLAY 0.872340 (-8650 4600);
PAINT AQUA (-8650 4600);
DISPLAY INVISIBLE (-8650 4600);
FORCEPROP 1 LAST HDL_POWER GND
J 0
(-8725 4800);
DISPLAY 1.170213 (-8725 4800);
PAINT GREEN (-8725 4800);
DISPLAY INVISIBLE (-8725 4800);
FORCEPROP 1 LAST PATH I25
J 0
(-8650 4650);
DISPLAY 0.872340 (-8650 4650);
PAINT AQUA (-8650 4650);
DISPLAY INVISIBLE (-8650 4650);
FORCEADD UNIVERSAL_GND..1
(-7950 4700);
FORCEPROP 3 LASTPIN (-7950 4750) SIG_NAME AGND_HSC\g
J 0
(-7940 4760);
DISPLAY 0.659574 (-7940 4760);
PAINT MONO (-7940 4760);
DISPLAY INVISIBLE (-7940 4760);
FORCEPROP 1 LAST HDL_POWER AGND_HSC
J 1
(-7925 4625);
DISPLAY 0.723404 (-7925 4625);
PAINT GREEN (-7925 4625);
FORCEPROP 2 LAST CDS_LIB pure_quanta_power
J 0
(-7950 4700);
DISPLAY INVISIBLE (-7950 4700);
FORCEPROP 1 LAST PATH I26
J 0
(-7875 4700);
DISPLAY 0.872340 (-7875 4700);
PAINT AQUA (-7875 4700);
DISPLAY INVISIBLE (-7875 4700);
FORCEADD Q_RES..1
(-8400 4900);
FORCEPROP 1 LAST LOCATION PR3002
J 0
(-8450 4950);
DISPLAY 0.723404 (-8450 4950);
PAINT AQUA (-8450 4950);
FORCEPROP 0 LAST $SEC 1
J 0
(-8275 5000);
DISPLAY 0.680851 (-8275 5000);
PAINT MONO (-8275 5000);
DISPLAY INVISIBLE (-8275 5000);
FORCEPROP 0 LAST CDS_SEC 1
J 0
(-8275 5000);
DISPLAY 1.021277 (-8275 5000);
DISPLAY INVISIBLE (-8275 5000);
FORCEPROP 1 LASTPIN (-8500 4900) $PN 1
J 0
(-8488 4912);
DISPLAY 0.787234 (-8488 4912);
PAINT MONO (-8488 4912);
FORCEPROP 1 LASTPIN (-8300 4900) $PN 2
J 0
(-8338 4912);
DISPLAY 0.787234 (-8338 4912);
PAINT MONO (-8338 4912);
FORCEPROP 1 LAST MATERIAL CHIP
J 0
(-8475 4725);
DISPLAY 0.723404 (-8475 4725);
PAINT SKYBLUE (-8475 4725);
FORCEPROP 1 LAST VALUE 0
J 2
(-8450 4825);
DISPLAY 0.723404 (-8450 4825);
PAINT SKYBLUE (-8450 4825);
FORCEPROP 1 LAST TOLERANCE 5%
J 0
(-8300 4825);
DISPLAY 0.723404 (-8300 4825);
PAINT SKYBLUE (-8300 4825);
FORCEPROP 1 LAST WATTAGE 1/16W
J 2
(-8500 4725);
DISPLAY 0.723404 (-8500 4725);
PAINT SKYBLUE (-8500 4725);
FORCEPROP 1 LAST PACK_TYPE 0402LF
J 0
(-8225 4725);
DISPLAY 0.723404 (-8225 4725);
PAINT SKYBLUE (-8225 4725);
FORCEPROP 2 LAST CDS_LIB pure_quanta
J 0
(-8400 4900);
DISPLAY INVISIBLE (-8400 4900);
FORCEPROP 1 LAST PATH I27
J 0
(-8450 5050);
DISPLAY 0.978723 (-8450 5050);
PAINT WHITE (-8450 5050);
DISPLAY INVISIBLE (-8450 5050);
FORCEPROP 1 LAST PART_NUMBER CS00002JB13
J 0
(-8275 4950);
DISPLAY 0.723404 (-8275 4950);
PAINT WHITE (-8275 4950);
DISPLAY INVISIBLE (-8275 4950);
FORCEADD UNIVERSAL_GND..1
(-6200 4500);
FORCEPROP 3 LASTPIN (-6200 4550) SIG_NAME GND\g
J 0
(-6190 4560);
DISPLAY 0.659574 (-6190 4560);
PAINT MONO (-6190 4560);
DISPLAY INVISIBLE (-6190 4560);
FORCEPROP 2 LAST CDS_LIB pure_quanta_power
J 0
(-6200 4500);
DISPLAY INVISIBLE (-6200 4500);
FORCEPROP 1 LAST HDL_POWER GND
J 1
(-6175 4425);
DISPLAY 0.872340 (-6175 4425);
PAINT GREEN (-6175 4425);
DISPLAY INVISIBLE (-6175 4425);
FORCEPROP 1 LAST PATH I28
J 0
(-6125 4500);
DISPLAY 0.872340 (-6125 4500);
PAINT AQUA (-6125 4500);
DISPLAY INVISIBLE (-6125 4500);
FORCEADD Q_RES..2
(-6200 4800);
FORCEPROP 1 LAST LOCATION R2227
J 0
(-6155 4925);
DISPLAY 0.638298 (-6155 4925);
FORCEPROP 0 LAST $SEC 1
J 0
(-6150 4975);
DISPLAY 0.680851 (-6150 4975);
PAINT MONO (-6150 4975);
DISPLAY INVISIBLE (-6150 4975);
FORCEPROP 2 LAST CDS_SEC 1
J 0
(-6150 5025);
DISPLAY 0.680851 (-6150 5025);
DISPLAY INVISIBLE (-6150 5025);
FORCEPROP 1 LASTPIN (-6200 4900) $PN 1
J 0
(-6195 4862);
DISPLAY 0.787234 (-6195 4862);
PAINT MONO (-6195 4862);
FORCEPROP 1 LASTPIN (-6200 4700) $PN 2
J 0
(-6195 4710);
DISPLAY 0.787234 (-6195 4710);
PAINT MONO (-6195 4710);
FORCEPROP 1 LAST WATTAGE 1/16W
J 0
(-6160 4775);
DISPLAY 0.638298 (-6160 4775);
FORCEPROP 1 LAST VALUE 10K
J 0
(-6155 4875);
DISPLAY 0.638298 (-6155 4875);
FORCEPROP 1 LAST TOLERANCE 1%
J 0
(-6155 4825);
DISPLAY 0.638298 (-6155 4825);
FORCEPROP 1 LAST PACK_TYPE 0402LF
J 0
(-6160 4625);
DISPLAY 0.638298 (-6160 4625);
FORCEPROP 1 LAST MATERIAL EMPTY
J 0
(-6160 4725);
DISPLAY 0.638298 (-6160 4725);
PAINT RED (-6160 4725);
FORCEPROP 2 LAST CDS_LIB pure_quanta
J 0
(-6200 4800);
DISPLAY INVISIBLE (-6200 4800);
FORCEPROP 1 LAST PATH I29
J 0
(-6150 4975);
DISPLAY 0.978723 (-6150 4975);
PAINT WHITE (-6150 4975);
DISPLAY INVISIBLE (-6150 4975);
FORCEPROP 1 LAST PART_NUMBER CS31002FB08
J 0
(-6160 4675);
DISPLAY 0.638298 (-6160 4675);
DISPLAY INVISIBLE (-6160 4675);
FORCEADD ZENER_AC..1
R 1
(-8075 5525);
FORCEPROP 1 LAST LOCATION PD13
J 0
(-8025 5475);
DISPLAY 0.723404 (-8025 5475);
PAINT AQUA (-8025 5475);
FORCEPROP 0 LAST $SEC 1
R 1
J 0
(-8025 5650);
DISPLAY 0.680851 (-8025 5650);
PAINT MONO (-8025 5650);
DISPLAY INVISIBLE (-8025 5650);
FORCEPROP 0 LAST CDS_SEC 1
R 1
J 0
(-8025 5650);
DISPLAY 1.021277 (-8025 5650);
DISPLAY INVISIBLE (-8025 5650);
FORCEPROP 0 LASTPIN (-8075 5400) $PN A
R 1
J 2
(-8085 5390);
DISPLAY 0.680851 (-8085 5390);
PAINT MONO (-8085 5390);
FORCEPROP 0 LASTPIN (-8075 5650) $PN C
R 1
J 0
(-8085 5660);
DISPLAY 0.680851 (-8085 5660);
PAINT MONO (-8085 5660);
FORCEPROP 2 LAST VALUE 5.0SMDJ14A
J 0
(-8025 5525);
DISPLAY 0.723404 (-8025 5525);
PAINT SKYBLUE (-8025 5525);
FORCEPROP 1 LAST MATERIAL IC
J 0
(-8025 5375);
DISPLAY 0.723404 (-8025 5375);
PAINT SKYBLUE (-8025 5375);
FORCEPROP 2 LAST PART_TYPE SMLF
J 0
(-8025 5575);
DISPLAY 1.021277 (-8025 5575);
FORCEPROP 1 LAST NEEDS_NO_SIZE TRUE
R 1
J 0
(-8075 5525);
DISPLAY 0.723404 (-8075 5525);
PAINT GREEN (-8075 5525);
DISPLAY INVISIBLE (-8075 5525);
FORCEPROP 2 LAST CDS_LIB pure_quanta
J 0
(-8075 5525);
DISPLAY INVISIBLE (-8075 5525);
FORCEPROP 1 LAST CDS_LMAN_SYM_OUTLINE -75,50,75,-50
R 1
J 0
(-8075 5525);
DISPLAY 0.468085 (-8075 5525);
PAINT GREEN (-8075 5525);
DISPLAY INVISIBLE (-8075 5525);
FORCEPROP 1 LAST PATH I3
R 1
J 0
(-8075 5525);
DISPLAY 0.723404 (-8075 5525);
PAINT GREEN (-8075 5525);
DISPLAY INVISIBLE (-8075 5525);
FORCEPROP 1 LAST PART_NUMBER BC0MDJ14000
J 0
(-8025 5425);
DISPLAY 0.723404 (-8025 5425);
PAINT WHITE (-8025 5425);
DISPLAY INVISIBLE (-8025 5425);
FORCEADD Q_RES..2
(-6200 5550);
FORCEPROP 1 LAST LOCATION R2219
J 0
(-6155 5675);
DISPLAY 0.723404 (-6155 5675);
PAINT AQUA (-6155 5675);
FORCEPROP 2 LAST $SEC 1
J 0
(-6150 5775);
DISPLAY 0.680851 (-6150 5775);
PAINT MONO (-6150 5775);
DISPLAY INVISIBLE (-6150 5775);
FORCEPROP 0 LAST CDS_SEC 1
J 0
(-6150 5775);
DISPLAY 0.680851 (-6150 5775);
PAINT MONO (-6150 5775);
DISPLAY INVISIBLE (-6150 5775);
FORCEPROP 1 LASTPIN (-6200 5650) $PN 1
J 0
(-6195 5612);
DISPLAY 0.723404 (-6195 5612);
PAINT MONO (-6195 5612);
FORCEPROP 1 LASTPIN (-6200 5450) $PN 2
J 0
(-6195 5460);
DISPLAY 0.723404 (-6195 5460);
PAINT MONO (-6195 5460);
FORCEPROP 1 LAST TOLERANCE 1%
J 0
(-6155 5575);
DISPLAY 0.723404 (-6155 5575);
PAINT SKYBLUE (-6155 5575);
FORCEPROP 1 LAST WATTAGE 1/16W
J 0
(-6160 5525);
DISPLAY 0.723404 (-6160 5525);
PAINT SKYBLUE (-6160 5525);
FORCEPROP 1 LAST MATERIAL EMPTY
J 0
(-6160 5475);
DISPLAY 0.723404 (-6160 5475);
PAINT RED (-6160 5475);
FORCEPROP 1 LAST PACK_TYPE 0402LF
J 0
(-6160 5375);
DISPLAY 0.723404 (-6160 5375);
PAINT SKYBLUE (-6160 5375);
FORCEPROP 1 LAST VALUE 267K
J 0
(-6155 5625);
DISPLAY 0.723404 (-6155 5625);
PAINT SKYBLUE (-6155 5625);
FORCEPROP 2 LAST CDS_LIB pure_quanta
J 0
(-6200 5550);
DISPLAY INVISIBLE (-6200 5550);
FORCEPROP 1 LAST PATH I30
J 0
(-6150 5725);
DISPLAY 0.978723 (-6150 5725);
PAINT WHITE (-6150 5725);
DISPLAY INVISIBLE (-6150 5725);
FORCEPROP 1 LAST PART_NUMBER CS42672FB03
J 0
(-6160 5425);
DISPLAY 0.723404 (-6160 5425);
PAINT WHITE (-6160 5425);
DISPLAY INVISIBLE (-6160 5425);
FORCEADD UNIVERSAL_POWER..1
(-6200 5900);
FORCEPROP 3 LASTPIN (-6200 5850) SIG_NAME P12V_AUX\g
J 0
(-6190 5860);
DISPLAY 0.659574 (-6190 5860);
PAINT MONO (-6190 5860);
DISPLAY INVISIBLE (-6190 5860);
FORCEPROP 1 LAST HDL_POWER P12V_AUX
J 1
(-6200 5950);
DISPLAY 0.723404 (-6200 5950);
PAINT GREEN (-6200 5950);
FORCEPROP 2 LAST CDS_LIB pure_quanta_power
J 0
(-6200 5900);
PAINT MONO (-6200 5900);
DISPLAY INVISIBLE (-6200 5900);
FORCEPROP 1 LAST PATH I31
J 0
(-6150 5925);
DISPLAY 0.872340 (-6150 5925);
PAINT AQUA (-6150 5925);
DISPLAY INVISIBLE (-6150 5925);
FORCEADD UNIVERSAL_GND..1
(-5600 4500);
FORCEPROP 3 LASTPIN (-5600 4550) SIG_NAME GND\g
J 0
(-5590 4560);
DISPLAY 0.659574 (-5590 4560);
PAINT MONO (-5590 4560);
DISPLAY INVISIBLE (-5590 4560);
FORCEPROP 2 LAST CDS_LIB pure_quanta_power
J 0
(-5600 4500);
DISPLAY INVISIBLE (-5600 4500);
FORCEPROP 1 LAST HDL_POWER GND
J 1
(-5575 4425);
DISPLAY 0.872340 (-5575 4425);
PAINT GREEN (-5575 4425);
DISPLAY INVISIBLE (-5575 4425);
FORCEPROP 1 LAST PATH I32
J 0
(-5525 4500);
DISPLAY 0.872340 (-5525 4500);
PAINT AQUA (-5525 4500);
DISPLAY INVISIBLE (-5525 4500);
FORCEADD Q_RES..2
(-5600 4800);
FORCEPROP 1 LAST LOCATION R2222
J 0
(-5555 4925);
DISPLAY 0.723404 (-5555 4925);
PAINT AQUA (-5555 4925);
FORCEPROP 2 LAST $SEC 1
J 0
(-5550 5025);
DISPLAY 0.680851 (-5550 5025);
PAINT MONO (-5550 5025);
DISPLAY INVISIBLE (-5550 5025);
FORCEPROP 0 LAST CDS_SEC 1
J 0
(-5550 5025);
DISPLAY 0.680851 (-5550 5025);
PAINT MONO (-5550 5025);
DISPLAY INVISIBLE (-5550 5025);
FORCEPROP 1 LASTPIN (-5600 4900) $PN 1
J 0
(-5595 4862);
DISPLAY 0.723404 (-5595 4862);
PAINT MONO (-5595 4862);
FORCEPROP 1 LASTPIN (-5600 4700) $PN 2
J 0
(-5595 4710);
DISPLAY 0.723404 (-5595 4710);
PAINT MONO (-5595 4710);
FORCEPROP 1 LAST VALUE 1K
J 0
(-5555 4875);
DISPLAY 0.723404 (-5555 4875);
PAINT SKYBLUE (-5555 4875);
FORCEPROP 1 LAST PACK_TYPE 0402LF
J 0
(-5560 4625);
DISPLAY 0.723404 (-5560 4625);
PAINT SKYBLUE (-5560 4625);
FORCEPROP 1 LAST TOLERANCE 1%
J 0
(-5555 4825);
DISPLAY 0.723404 (-5555 4825);
PAINT SKYBLUE (-5555 4825);
FORCEPROP 1 LAST MATERIAL EMPTY
J 0
(-5560 4725);
DISPLAY 0.723404 (-5560 4725);
PAINT RED (-5560 4725);
FORCEPROP 1 LAST WATTAGE 1/16W
J 0
(-5560 4775);
DISPLAY 0.723404 (-5560 4775);
PAINT SKYBLUE (-5560 4775);
FORCEPROP 2 LAST CDS_LIB pure_quanta
J 0
(-5600 4800);
DISPLAY INVISIBLE (-5600 4800);
FORCEPROP 1 LAST PATH I33
J 0
(-5550 4975);
DISPLAY 0.978723 (-5550 4975);
PAINT WHITE (-5550 4975);
DISPLAY INVISIBLE (-5550 4975);
FORCEPROP 1 LAST PART_NUMBER CS21002FB06
J 0
(-5560 4675);
DISPLAY 0.723404 (-5560 4675);
PAINT WHITE (-5560 4675);
DISPLAY INVISIBLE (-5560 4675);
FORCEADD Q_RES..2
(-5600 5550);
FORCEPROP 1 LAST LOCATION R2221
J 0
(-5555 5675);
DISPLAY 0.723404 (-5555 5675);
PAINT AQUA (-5555 5675);
FORCEPROP 2 LAST $SEC 1
J 0
(-5550 5775);
DISPLAY 0.680851 (-5550 5775);
PAINT MONO (-5550 5775);
DISPLAY INVISIBLE (-5550 5775);
FORCEPROP 0 LAST CDS_SEC 1
J 0
(-5550 5775);
DISPLAY 0.680851 (-5550 5775);
PAINT MONO (-5550 5775);
DISPLAY INVISIBLE (-5550 5775);
FORCEPROP 1 LASTPIN (-5600 5650) $PN 1
J 0
(-5595 5612);
DISPLAY 0.723404 (-5595 5612);
PAINT MONO (-5595 5612);
FORCEPROP 1 LASTPIN (-5600 5450) $PN 2
J 0
(-5595 5460);
DISPLAY 0.723404 (-5595 5460);
PAINT MONO (-5595 5460);
FORCEPROP 1 LAST TOLERANCE 1%
J 0
(-5555 5575);
DISPLAY 0.723404 (-5555 5575);
PAINT SKYBLUE (-5555 5575);
FORCEPROP 1 LAST VALUE 26.7K
J 0
(-5555 5625);
DISPLAY 0.723404 (-5555 5625);
PAINT SKYBLUE (-5555 5625);
FORCEPROP 1 LAST MATERIAL EMPTY
J 0
(-5560 5475);
DISPLAY 0.723404 (-5560 5475);
PAINT RED (-5560 5475);
FORCEPROP 1 LAST PACK_TYPE 0402LF
J 0
(-5560 5375);
DISPLAY 0.723404 (-5560 5375);
PAINT SKYBLUE (-5560 5375);
FORCEPROP 1 LAST WATTAGE 1/16W
J 0
(-5560 5525);
DISPLAY 0.723404 (-5560 5525);
PAINT SKYBLUE (-5560 5525);
FORCEPROP 2 LAST CDS_LIB pure_quanta
J 0
(-5600 5550);
DISPLAY INVISIBLE (-5600 5550);
FORCEPROP 1 LAST PATH I35
J 0
(-5550 5725);
DISPLAY 0.978723 (-5550 5725);
PAINT WHITE (-5550 5725);
DISPLAY INVISIBLE (-5550 5725);
FORCEPROP 1 LAST PART_NUMBER CS32672FB03
J 0
(-5560 5425);
DISPLAY 0.723404 (-5560 5425);
PAINT WHITE (-5560 5425);
DISPLAY INVISIBLE (-5560 5425);
FORCEADD UNIVERSAL_POWER..1
(-5600 5900);
FORCEPROP 3 LASTPIN (-5600 5850) SIG_NAME P12V_AUX\g
J 0
(-5590 5860);
DISPLAY 0.659574 (-5590 5860);
PAINT MONO (-5590 5860);
DISPLAY INVISIBLE (-5590 5860);
FORCEPROP 1 LAST HDL_POWER P12V_AUX
J 1
(-5600 5950);
DISPLAY 0.723404 (-5600 5950);
PAINT GREEN (-5600 5950);
FORCEPROP 2 LAST CDS_LIB pure_quanta_power
J 0
(-5600 5900);
PAINT MONO (-5600 5900);
DISPLAY INVISIBLE (-5600 5900);
FORCEPROP 1 LAST PATH I36
J 0
(-5550 5925);
DISPLAY 0.872340 (-5550 5925);
PAINT AQUA (-5550 5925);
DISPLAY INVISIBLE (-5550 5925);
FORCEADD UNIVERSAL_GND..1
(-3375 4825);
FORCEPROP 3 LASTPIN (-3375 4875) SIG_NAME GND\g
J 0
(-3365 4885);
DISPLAY 0.659574 (-3365 4885);
PAINT MONO (-3365 4885);
DISPLAY INVISIBLE (-3365 4885);
FORCEPROP 2 LAST CDS_LIB pure_quanta_power
J 0
(-3375 4825);
DISPLAY INVISIBLE (-3375 4825);
FORCEPROP 1 LAST HDL_POWER GND
J 1
(-3350 4750);
DISPLAY 0.872340 (-3350 4750);
PAINT GREEN (-3350 4750);
DISPLAY INVISIBLE (-3350 4750);
FORCEPROP 1 LAST PATH I39
J 0
(-3300 4825);
DISPLAY 0.872340 (-3300 4825);
PAINT AQUA (-3300 4825);
DISPLAY INVISIBLE (-3300 4825);
FORCEADD GND..1
(-7525 5275);
FORCEPROP 3 LASTPIN (-7525 5325) SIG_NAME GND\g
J 0
(-7515 5335);
DISPLAY 0.659574 (-7515 5335);
PAINT MONO (-7515 5335);
DISPLAY INVISIBLE (-7515 5335);
FORCEPROP 2 LAST ROOM VR_DDR1_POWER_STAGE
J 0
(-7750 5350);
DISPLAY INVISIBLE (-7750 5350);
FORCEPROP 2 LAST CDS_LIB pure_quanta_power
J 0
(-7525 5275);
DISPLAY INVISIBLE (-7525 5275);
FORCEPROP 1 LAST SIZE 1B
J 0
(-7450 5225);
DISPLAY 0.872340 (-7450 5225);
PAINT AQUA (-7450 5225);
DISPLAY INVISIBLE (-7450 5225);
FORCEPROP 1 LAST HDL_POWER GND
J 0
(-7525 5425);
DISPLAY 1.170213 (-7525 5425);
PAINT GREEN (-7525 5425);
DISPLAY INVISIBLE (-7525 5425);
FORCEPROP 1 LAST PATH I4
J 0
(-7450 5275);
DISPLAY 0.872340 (-7450 5275);
PAINT AQUA (-7450 5275);
DISPLAY INVISIBLE (-7450 5275);
FORCEADD OFFPAGE..2
(-2100 5150);
FORCEPROP 2 LAST $XR1 80 
J 0
(-1791 5150);
DISPLAY 0.638298 (-1791 5150);
PAINT MONO (-1791 5150);
FORCEPROP 2 LAST $XR0 269 
J 0
(-1911 5150);
DISPLAY 0.638298 (-1911 5150);
PAINT MONO (-1911 5150);
FORCEPROP 2 LAST CDS_LIB standard
J 0
(-2100 5150);
DISPLAY INVISIBLE (-2100 5150);
FORCEPROP 1 LAST OFFPAGE TRUE
J 0
(-1775 5025);
DISPLAY 0.872340 (-1775 5025);
PAINT AQUA (-1775 5025);
DISPLAY INVISIBLE (-1775 5025);
FORCEPROP 1 LAST COMMENT_BODY TRUE
J 0
(-2145 5055);
DISPLAY 0.872340 (-2145 5055);
PAINT GREEN (-2145 5055);
DISPLAY INVISIBLE (-2145 5055);
FORCEPROP 2 LAST PATH I40
J 0
(-1900 5200);
DISPLAY 0.680851 (-1900 5200);
DISPLAY INVISIBLE (-1900 5200);
FORCEADD UNIVERSAL_GND..1
(-1625 4775);
FORCEPROP 3 LASTPIN (-1625 4825) SIG_NAME GND\g
J 0
(-1615 4835);
DISPLAY 0.659574 (-1615 4835);
PAINT MONO (-1615 4835);
DISPLAY INVISIBLE (-1615 4835);
FORCEPROP 2 LAST CDS_LIB pure_quanta_power
J 0
(-1625 4775);
DISPLAY INVISIBLE (-1625 4775);
FORCEPROP 1 LAST HDL_POWER GND
J 1
(-1600 4700);
DISPLAY 0.872340 (-1600 4700);
PAINT GREEN (-1600 4700);
DISPLAY INVISIBLE (-1600 4700);
FORCEPROP 1 LAST PATH I41
J 0
(-1550 4775);
DISPLAY 0.872340 (-1550 4775);
PAINT AQUA (-1550 4775);
DISPLAY INVISIBLE (-1550 4775);
FORCEADD MOSFET_N..1
(-1675 5150);
FORCEPROP 1 LAST LOCATION U325
J 0
(-1503 4841);
DISPLAY 0.723404 (-1503 4841);
PAINT GREEN (-1503 4841);
FORCEPROP 0 LAST $SEC 1
J 0
(-1500 5075);
DISPLAY 0.680851 (-1500 5075);
PAINT MONO (-1500 5075);
DISPLAY INVISIBLE (-1500 5075);
FORCEPROP 0 LAST CDS_SEC 1
J 0
(-1500 5075);
DISPLAY 1.021277 (-1500 5075);
DISPLAY INVISIBLE (-1500 5075);
FORCEPROP 1 LASTPIN (-1625 5250) $PN D
R 1
J 0
(-1625 5243);
DISPLAY 0.659574 (-1625 5243);
PAINT MONO (-1625 5243);
FORCEPROP 1 LASTPIN (-1775 5050) $PN G
J 2
(-1765 5053);
DISPLAY 0.659574 (-1765 5053);
PAINT MONO (-1765 5053);
FORCEPROP 1 LASTPIN (-1625 4950) $PN S
R 1
J 2
(-1625 4963);
DISPLAY 0.659574 (-1625 4963);
PAINT MONO (-1625 4963);
FORCEPROP 1 LAST MATERIAL EMPTY
J 0
(-1503 4681);
DISPLAY 0.723404 (-1503 4681);
PAINT RED (-1503 4681);
FORCEPROP 1 LAST VALUE BSS138K
J 0
(-1503 4921);
DISPLAY 0.723404 (-1503 4921);
PAINT GREEN (-1503 4921);
FORCEPROP 2 LAST MANUF_PN BSS138K
J 0
(-1500 5025);
DISPLAY 1.021277 (-1500 5025);
FORCEPROP 2 LAST PATH I42
J 0
(-1500 5075);
DISPLAY 0.680851 (-1500 5075);
FORCEPROP 1 LAST CDS_LMAN_SYM_OUTLINE -50,50,100,-150
J 0
(-1675 5150);
DISPLAY 0.468085 (-1675 5150);
PAINT GREEN (-1675 5150);
DISPLAY INVISIBLE (-1675 5150);
FORCEPROP 2 LAST CDS_LIB pure_quanta
J 0
(-1675 5150);
DISPLAY INVISIBLE (-1675 5150);
FORCEPROP 1 LAST PACK_TYPE SMLF
J 0
(-1650 4900);
DISPLAY 0.723404 (-1650 4900);
PAINT GREEN (-1650 4900);
DISPLAY INVISIBLE (-1650 4900);
FORCEPROP 1 LAST PART_NUMBER BAM138K0000
J 0
(-1503 4761);
DISPLAY 0.723404 (-1503 4761);
PAINT GREEN (-1503 4761);
DISPLAY INVISIBLE (-1503 4761);
FORCEADD Q_RES..2
(-3275 5525);
FORCEPROP 1 LAST LOCATION R2230
J 0
(-3230 5650);
DISPLAY 0.723404 (-3230 5650);
PAINT AQUA (-3230 5650);
FORCEPROP 2 LAST $SEC 1
J 0
(-3225 5750);
DISPLAY 0.680851 (-3225 5750);
PAINT MONO (-3225 5750);
DISPLAY INVISIBLE (-3225 5750);
FORCEPROP 2 LAST CDS_SEC 1
J 0
(-3225 5750);
DISPLAY 0.680851 (-3225 5750);
DISPLAY INVISIBLE (-3225 5750);
FORCEPROP 1 LASTPIN (-3275 5625) $PN 1
J 0
(-3270 5587);
DISPLAY 0.723404 (-3270 5587);
PAINT WHITE (-3270 5587);
FORCEPROP 1 LASTPIN (-3275 5425) $PN 2
J 0
(-3270 5435);
DISPLAY 0.723404 (-3270 5435);
PAINT WHITE (-3270 5435);
FORCEPROP 1 LAST TOLERANCE 1%
J 0
(-3230 5550);
DISPLAY 0.723404 (-3230 5550);
PAINT SKYBLUE (-3230 5550);
FORCEPROP 1 LAST WATTAGE 1/16W
J 0
(-3235 5500);
DISPLAY 0.723404 (-3235 5500);
PAINT SKYBLUE (-3235 5500);
FORCEPROP 1 LAST MATERIAL EMPTY
J 0
(-3235 5450);
DISPLAY 0.723404 (-3235 5450);
PAINT RED (-3235 5450);
FORCEPROP 1 LAST PACK_TYPE 0402LF
J 0
(-3225 5400);
DISPLAY 0.723404 (-3225 5400);
PAINT SKYBLUE (-3225 5400);
FORCEPROP 1 LAST VALUE 10K
J 0
(-3230 5600);
DISPLAY 0.723404 (-3230 5600);
PAINT SKYBLUE (-3230 5600);
FORCEPROP 2 LAST CDS_LIB pure_quanta
J 0
(-3275 5525);
DISPLAY INVISIBLE (-3275 5525);
FORCEPROP 1 LAST PATH I43
J 0
(-3225 5700);
DISPLAY 0.978723 (-3225 5700);
PAINT WHITE (-3225 5700);
DISPLAY INVISIBLE (-3225 5700);
FORCEPROP 1 LAST PART_NUMBER CS31002FB08
J 0
(-3235 5400);
DISPLAY 0.723404 (-3235 5400);
PAINT WHITE (-3235 5400);
DISPLAY INVISIBLE (-3235 5400);
FORCEADD UNIVERSAL_POWER..1
(-3275 5900);
FORCEPROP 3 LASTPIN (-3275 5850) SIG_NAME P3V3_AUX\g
J 0
(-3265 5860);
DISPLAY 0.659574 (-3265 5860);
PAINT MONO (-3265 5860);
DISPLAY INVISIBLE (-3265 5860);
FORCEPROP 1 LAST HDL_POWER P3V3_AUX
J 1
(-3275 5950);
DISPLAY 0.723404 (-3275 5950);
PAINT GREEN (-3275 5950);
FORCEPROP 2 LAST CDS_LIB pure_quanta_power
J 0
(-3275 5900);
PAINT MONO (-3275 5900);
DISPLAY INVISIBLE (-3275 5900);
FORCEPROP 1 LAST PATH I44
J 0
(-3225 5925);
DISPLAY 0.872340 (-3225 5925);
PAINT AQUA (-3225 5925);
DISPLAY INVISIBLE (-3225 5925);
FORCEADD Q_RES..2
(-2975 5550);
FORCEPROP 1 LAST LOCATION R2233
J 0
(-2930 5675);
DISPLAY 0.723404 (-2930 5675);
PAINT AQUA (-2930 5675);
FORCEPROP 2 LAST $SEC 1
J 0
(-2925 5775);
DISPLAY 0.680851 (-2925 5775);
PAINT MONO (-2925 5775);
DISPLAY INVISIBLE (-2925 5775);
FORCEPROP 2 LAST CDS_SEC 1
J 0
(-2925 5775);
DISPLAY 0.680851 (-2925 5775);
DISPLAY INVISIBLE (-2925 5775);
FORCEPROP 1 LASTPIN (-2975 5650) $PN 1
J 0
(-2970 5612);
DISPLAY 0.723404 (-2970 5612);
PAINT WHITE (-2970 5612);
FORCEPROP 1 LASTPIN (-2975 5450) $PN 2
J 0
(-2970 5460);
DISPLAY 0.723404 (-2970 5460);
PAINT WHITE (-2970 5460);
FORCEPROP 1 LAST WATTAGE 1/16W
J 0
(-2935 5525);
DISPLAY 0.723404 (-2935 5525);
PAINT SKYBLUE (-2935 5525);
FORCEPROP 1 LAST TOLERANCE 1%
J 0
(-2930 5575);
DISPLAY 0.723404 (-2930 5575);
PAINT SKYBLUE (-2930 5575);
FORCEPROP 1 LAST MATERIAL EMPTY
J 0
(-2935 5475);
DISPLAY 0.723404 (-2935 5475);
PAINT RED (-2935 5475);
FORCEPROP 1 LAST VALUE 1K
J 0
(-2930 5625);
DISPLAY 0.723404 (-2930 5625);
PAINT SKYBLUE (-2930 5625);
FORCEPROP 1 LAST PACK_TYPE 0402LF
J 0
(-2925 5425);
DISPLAY 0.723404 (-2925 5425);
PAINT SKYBLUE (-2925 5425);
FORCEPROP 2 LAST CDS_LIB pure_quanta
J 0
(-2975 5550);
DISPLAY INVISIBLE (-2975 5550);
FORCEPROP 1 LAST PATH I45
J 0
(-2925 5725);
DISPLAY 0.978723 (-2925 5725);
PAINT WHITE (-2925 5725);
DISPLAY INVISIBLE (-2925 5725);
FORCEPROP 1 LAST PART_NUMBER CS21002FB06
J 0
(-2935 5425);
DISPLAY 0.723404 (-2935 5425);
PAINT WHITE (-2935 5425);
DISPLAY INVISIBLE (-2935 5425);
FORCEADD Q_RES..2
(-1625 5725);
FORCEPROP 1 LAST LOCATION R4620
J 0
(-1570 5875);
DISPLAY 0.638298 (-1570 5875);
FORCEPROP 0 LAST $SEC 1
J 0
(-1550 5925);
DISPLAY 0.680851 (-1550 5925);
PAINT MONO (-1550 5925);
DISPLAY INVISIBLE (-1550 5925);
FORCEPROP 0 LAST CDS_SEC 1
J 0
(-1550 5925);
DISPLAY 1.021277 (-1550 5925);
DISPLAY INVISIBLE (-1550 5925);
FORCEPROP 1 LASTPIN (-1625 5825) $PN 1
J 0
(-1620 5787);
DISPLAY 0.787234 (-1620 5787);
PAINT MONO (-1620 5787);
FORCEPROP 1 LASTPIN (-1625 5625) $PN 2
J 0
(-1620 5635);
DISPLAY 0.787234 (-1620 5635);
PAINT MONO (-1620 5635);
FORCEPROP 1 LAST WATTAGE 1/16W
J 0
(-1575 5725);
DISPLAY 0.638298 (-1575 5725);
FORCEPROP 1 LAST TOLERANCE 1%
J 0
(-1570 5775);
DISPLAY 0.638298 (-1570 5775);
FORCEPROP 1 LAST VALUE 1K
J 0
(-1570 5825);
DISPLAY 0.638298 (-1570 5825);
FORCEPROP 1 LAST PACK_TYPE 0402LF
J 0
(-1575 5575);
DISPLAY 0.638298 (-1575 5575);
FORCEPROP 1 LAST MATERIAL EMPTY
J 0
(-1575 5675);
DISPLAY 0.638298 (-1575 5675);
PAINT RED (-1575 5675);
FORCEPROP 2 LAST CDS_LIB pure_quanta
J 0
(-1625 5725);
DISPLAY INVISIBLE (-1625 5725);
FORCEPROP 1 LAST PATH I46
J 0
(-1575 5900);
DISPLAY 0.978723 (-1575 5900);
PAINT WHITE (-1575 5900);
DISPLAY INVISIBLE (-1575 5900);
FORCEPROP 1 LAST PART_NUMBER CS21002FB06
J 0
(-1575 5625);
DISPLAY 0.638298 (-1575 5625);
DISPLAY INVISIBLE (-1575 5625);
FORCEADD UNIVERSAL_POWER..1
(-1625 5950);
FORCEPROP 3 LASTPIN (-1625 5900) SIG_NAME P3V3_AUX\g
J 0
(-1615 5910);
DISPLAY 0.659574 (-1615 5910);
PAINT MONO (-1615 5910);
DISPLAY INVISIBLE (-1615 5910);
FORCEPROP 1 LAST HDL_POWER P3V3_AUX
J 1
(-1625 6000);
DISPLAY 0.723404 (-1625 6000);
PAINT GREEN (-1625 6000);
FORCEPROP 2 LAST CDS_LIB pure_quanta_power
J 0
(-1625 5950);
DISPLAY INVISIBLE (-1625 5950);
FORCEPROP 1 LAST PATH I47
J 0
(-1575 5975);
DISPLAY 0.872340 (-1575 5975);
PAINT AQUA (-1575 5975);
DISPLAY INVISIBLE (-1575 5975);
FORCEADD OFFPAGE..2
(-375 5475);
FORCEPROP 2 LAST $XR1 80 
J 0
(-186 5439);
DISPLAY 0.638298 (-186 5439);
PAINT MONO (-186 5439);
FORCEPROP 2 LAST $XR0 269 
J 0
(-186 5475);
DISPLAY 0.638298 (-186 5475);
PAINT MONO (-186 5475);
FORCEPROP 2 LAST CDS_LIB standard
J 0
(-375 5475);
DISPLAY INVISIBLE (-375 5475);
FORCEPROP 1 LAST OFFPAGE TRUE
J 0
(-50 5350);
DISPLAY 0.872340 (-50 5350);
PAINT AQUA (-50 5350);
DISPLAY INVISIBLE (-50 5350);
FORCEPROP 1 LAST COMMENT_BODY TRUE
J 0
(-420 5380);
DISPLAY 0.872340 (-420 5380);
PAINT GREEN (-420 5380);
DISPLAY INVISIBLE (-420 5380);
FORCEPROP 2 LAST PATH I48
J 0
(-175 5525);
DISPLAY 0.680851 (-175 5525);
DISPLAY INVISIBLE (-175 5525);
FORCEADD LT6700CS61TRPBF..1
(-3825 5100);
FORCEPROP 1 LAST LOCATION U206
J 0
(-4044 5531);
DISPLAY 0.723404 (-4044 5531);
PAINT GREEN (-4044 5531);
FORCEPROP 0 LAST $SEC 1
J 0
(-4050 5650);
DISPLAY 0.680851 (-4050 5650);
PAINT MONO (-4050 5650);
DISPLAY INVISIBLE (-4050 5650);
FORCEPROP 0 LAST CDS_SEC 1
J 0
(-4050 5650);
DISPLAY 1.021277 (-4050 5650);
DISPLAY INVISIBLE (-4050 5650);
FORCEPROP 0 LASTPIN (-3450 5000) $PN 2
J 0
(-3440 5010);
DISPLAY 0.680851 (-3440 5010);
PAINT MONO (-3440 5010);
FORCEPROP 0 LASTPIN (-4200 5150) $PN 3
J 2
(-4210 5160);
DISPLAY 0.680851 (-4210 5160);
PAINT MONO (-4210 5160);
FORCEPROP 0 LASTPIN (-4200 5050) $PN 4
J 2
(-4210 5060);
DISPLAY 0.680851 (-4210 5060);
PAINT MONO (-4210 5060);
FORCEPROP 0 LASTPIN (-3450 5150) $PN 1
J 0
(-3440 5160);
DISPLAY 0.680851 (-3440 5160);
PAINT MONO (-3440 5160);
FORCEPROP 0 LASTPIN (-3450 5050) $PN 6
J 0
(-3440 5060);
DISPLAY 0.680851 (-3440 5060);
PAINT MONO (-3440 5060);
FORCEPROP 0 LASTPIN (-4200 5200) $PN 5
J 2
(-4210 5210);
DISPLAY 0.680851 (-4210 5210);
PAINT MONO (-4210 5210);
FORCEPROP 1 LAST MATERIAL EMPTY
J 0
(-4044 5257);
DISPLAY 0.723404 (-4044 5257);
PAINT RED (-4044 5257);
FORCEPROP 2 LAST PART_TYPE SMLF
J 0
(-4050 5600);
DISPLAY 1.021277 (-4050 5600);
FORCEPROP 2 LAST VALUE LT6700CS6-1#TRPBF
J 0
(-4225 5425);
DISPLAY 1.021277 (-4225 5425);
FORCEPROP 2 LAST CDS_LIB pure_quanta
J 0
(-3825 5100);
DISPLAY INVISIBLE (-3825 5100);
FORCEPROP 1 LAST CDS_LMAN_SYM_OUTLINE -225,150,225,-150
J 0
(-3825 5100);
DISPLAY 0.468085 (-3825 5100);
PAINT GREEN (-3825 5100);
DISPLAY INVISIBLE (-3825 5100);
FORCEPROP 1 LAST NEEDS_NO_SIZE TRUE
J 0
(-3825 5100);
DISPLAY 0.723404 (-3825 5100);
PAINT GREEN (-3825 5100);
DISPLAY INVISIBLE (-3825 5100);
FORCEPROP 1 LAST PATH I49
J 0
(-3825 5100);
DISPLAY 0.723404 (-3825 5100);
PAINT GREEN (-3825 5100);
DISPLAY INVISIBLE (-3825 5100);
FORCEPROP 1 LAST PART_NUMBER AL006700001
J 0
(-4044 5384);
DISPLAY 0.723404 (-4044 5384);
PAINT GREEN (-4044 5384);
DISPLAY INVISIBLE (-4044 5384);
FORCEADD UNIVERSAL_POWER..1
(-8075 6150);
FORCEPROP 3 LASTPIN (-8075 6100) SIG_NAME P12V_PSU\g
J 0
(-8065 6110);
DISPLAY 0.659574 (-8065 6110);
PAINT MONO (-8065 6110);
DISPLAY INVISIBLE (-8065 6110);
FORCEPROP 1 LAST HDL_POWER P12V_PSU
J 1
(-8075 6200);
DISPLAY 0.723404 (-8075 6200);
PAINT GREEN (-8075 6200);
FORCEPROP 2 LAST ROOM AUX_SW
J 0
(-8075 6250);
DISPLAY 0.617021 (-8075 6250);
DISPLAY INVISIBLE (-8075 6250);
FORCEPROP 2 LAST BOM_COST MIO_VRD_SB
J 0
(-8075 6250);
DISPLAY 0.617021 (-8075 6250);
PAINT PURPLE (-8075 6250);
DISPLAY INVISIBLE (-8075 6250);
FORCEPROP 2 LAST CDS_LIB pure_quanta_power
J 0
(-8075 6150);
DISPLAY INVISIBLE (-8075 6150);
FORCEPROP 1 LAST PATH I5
J 0
(-8025 6175);
DISPLAY 0.872340 (-8025 6175);
PAINT AQUA (-8025 6175);
DISPLAY INVISIBLE (-8025 6175);
FORCEADD UNIVERSAL_GND..1
(-5475 2500);
FORCEPROP 3 LASTPIN (-5475 2550) SIG_NAME GND\g
J 0
(-5465 2560);
DISPLAY 0.659574 (-5465 2560);
PAINT MONO (-5465 2560);
DISPLAY INVISIBLE (-5465 2560);
FORCEPROP 2 LAST CDS_LIB pure_quanta_power
J 0
(-5475 2500);
DISPLAY INVISIBLE (-5475 2500);
FORCEPROP 1 LAST HDL_POWER GND
J 1
(-5450 2425);
DISPLAY 0.872340 (-5450 2425);
PAINT GREEN (-5450 2425);
DISPLAY INVISIBLE (-5450 2425);
FORCEPROP 1 LAST PATH I50
J 0
(-5400 2500);
DISPLAY 0.872340 (-5400 2500);
PAINT AQUA (-5400 2500);
DISPLAY INVISIBLE (-5400 2500);
FORCEADD LM4040AIM3X25NOPB..1
(-5100 2825);
FORCEPROP 1 LAST LOCATION U8007
J 0
(-5303 3203);
DISPLAY 0.723404 (-5303 3203);
PAINT GREEN (-5303 3203);
FORCEPROP 0 LAST $SEC 1
J 0
(-5300 3350);
DISPLAY 0.680851 (-5300 3350);
PAINT MONO (-5300 3350);
DISPLAY INVISIBLE (-5300 3350);
FORCEPROP 0 LAST CDS_SEC 1
J 0
(-5300 3350);
DISPLAY 1.021277 (-5300 3350);
DISPLAY INVISIBLE (-5300 3350);
FORCEPROP 0 LASTPIN (-5450 2975) $PN 1
J 2
(-5460 2985);
DISPLAY 0.680851 (-5460 2985);
PAINT MONO (-5460 2985);
FORCEPROP 0 LASTPIN (-5450 2675) $PN 2
J 2
(-5460 2685);
DISPLAY 0.680851 (-5460 2685);
PAINT MONO (-5460 2685);
FORCEPROP 0 LASTPIN (-4750 2825) $PN 3
J 0
(-4740 2835);
DISPLAY 0.680851 (-4740 2835);
PAINT MONO (-4740 2835);
FORCEPROP 2 LAST VALUE LM4040AIM3X-2.5/NOPB
J 0
(-5300 3250);
DISPLAY 0.808511 (-5300 3250);
FORCEPROP 1 LAST MATERIAL IC
J 0
(-5303 3080);
DISPLAY 0.723404 (-5303 3080);
PAINT GREEN (-5303 3080);
FORCEPROP 2 LAST PART_TYPE SMLF
J 0
(-5300 3300);
DISPLAY 0.808511 (-5300 3300);
FORCEPROP 2 LAST CDS_LIB pure_quanta
J 0
(-5100 2825);
DISPLAY INVISIBLE (-5100 2825);
FORCEPROP 1 LAST PIN_NAMES_ROTATE True
J 0
(-5100 2825);
DISPLAY 0.489362 (-5100 2825);
PAINT GREEN (-5100 2825);
DISPLAY INVISIBLE (-5100 2825);
FORCEPROP 1 LAST CDS_LMAN_SYM_OUTLINE -200,250,200,-250
J 0
(-5100 2825);
DISPLAY 0.468085 (-5100 2825);
PAINT GREEN (-5100 2825);
DISPLAY INVISIBLE (-5100 2825);
FORCEPROP 1 LAST PATH I51
J 0
(-5100 2825);
DISPLAY 0.723404 (-5100 2825);
PAINT GREEN (-5100 2825);
DISPLAY INVISIBLE (-5100 2825);
FORCEPROP 1 LAST PART_NUMBER AL404025013
J 0
(-5303 3169);
DISPLAY 0.723404 (-5303 3169);
PAINT GREEN (-5303 3169);
DISPLAY INVISIBLE (-5303 3169);
FORCEADD Q_RES..2
(-5500 3650);
FORCEPROP 1 LAST LOCATION R8113
J 0
(-5455 3775);
DISPLAY 0.978723 (-5455 3775);
FORCEPROP 0 LAST $SEC 1
J 0
(-5450 3825);
DISPLAY 0.680851 (-5450 3825);
PAINT MONO (-5450 3825);
DISPLAY INVISIBLE (-5450 3825);
FORCEPROP 0 LAST CDS_SEC 1
J 0
(-5450 3825);
DISPLAY 1.021277 (-5450 3825);
DISPLAY INVISIBLE (-5450 3825);
FORCEPROP 1 LASTPIN (-5500 3750) $PN 1
J 0
(-5495 3712);
DISPLAY 0.787234 (-5495 3712);
PAINT MONO (-5495 3712);
FORCEPROP 1 LASTPIN (-5500 3550) $PN 2
J 0
(-5495 3560);
DISPLAY 0.787234 (-5495 3560);
PAINT MONO (-5495 3560);
FORCEPROP 1 LAST PACK_TYPE 0402LF
J 0
(-5450 3525);
DISPLAY 0.723404 (-5450 3525);
FORCEPROP 1 LAST MATERIAL CHIP
J 0
(-5460 3575);
DISPLAY 0.723404 (-5460 3575);
FORCEPROP 1 LAST WATTAGE 1/16W
J 0
(-5460 3625);
DISPLAY 0.723404 (-5460 3625);
FORCEPROP 1 LAST TOLERANCE 1%
J 0
(-5455 3675);
DISPLAY 0.723404 (-5455 3675);
FORCEPROP 1 LAST VALUE 10K
J 0
(-5455 3725);
DISPLAY 0.723404 (-5455 3725);
FORCEPROP 2 LAST CDS_LIB pure_quanta
J 0
(-5500 3650);
DISPLAY INVISIBLE (-5500 3650);
FORCEPROP 1 LAST PATH I52
J 0
(-5450 3825);
DISPLAY 0.978723 (-5450 3825);
PAINT WHITE (-5450 3825);
DISPLAY INVISIBLE (-5450 3825);
FORCEPROP 1 LAST PART_NUMBER CS31002FB08
J 0
(-5460 3525);
DISPLAY 0.723404 (-5460 3525);
PAINT WHITE (-5460 3525);
DISPLAY INVISIBLE (-5460 3525);
FORCEADD UNIVERSAL_POWER..1
(-5500 3975);
FORCEPROP 3 LASTPIN (-5500 3925) SIG_NAME P3V3_AUX\g
J 0
(-5490 3935);
DISPLAY 0.659574 (-5490 3935);
PAINT MONO (-5490 3935);
DISPLAY INVISIBLE (-5490 3935);
FORCEPROP 1 LAST HDL_POWER P3V3_AUX
J 1
(-5500 4025);
DISPLAY 0.723404 (-5500 4025);
PAINT GREEN (-5500 4025);
FORCEPROP 2 LAST CDS_LIB pure_quanta_power
J 0
(-5500 3975);
DISPLAY INVISIBLE (-5500 3975);
FORCEPROP 1 LAST PATH I53
J 0
(-5450 4000);
DISPLAY 0.872340 (-5450 4000);
PAINT AQUA (-5450 4000);
DISPLAY INVISIBLE (-5450 4000);
FORCEADD UNIVERSAL_GND..1
(-4500 2750);
FORCEPROP 3 LASTPIN (-4500 2800) SIG_NAME GND\g
J 0
(-4490 2810);
DISPLAY 0.659574 (-4490 2810);
PAINT MONO (-4490 2810);
DISPLAY INVISIBLE (-4490 2810);
FORCEPROP 2 LAST CDS_LIB pure_quanta_power
J 0
(-4500 2750);
DISPLAY INVISIBLE (-4500 2750);
FORCEPROP 1 LAST HDL_POWER GND
J 1
(-4475 2675);
DISPLAY 0.872340 (-4475 2675);
PAINT GREEN (-4475 2675);
DISPLAY INVISIBLE (-4475 2675);
FORCEPROP 1 LAST PATH I54
J 0
(-4425 2750);
DISPLAY 0.872340 (-4425 2750);
PAINT AQUA (-4425 2750);
DISPLAY INVISIBLE (-4425 2750);
FORCEADD Q_RES..2
(-4500 3025);
FORCEPROP 1 LAST LOCATION R8115
J 0
(-4455 3150);
DISPLAY 1.021277 (-4455 3150);
FORCEPROP 0 LAST $SEC 1
J 0
(-4450 3200);
DISPLAY 0.680851 (-4450 3200);
PAINT MONO (-4450 3200);
DISPLAY INVISIBLE (-4450 3200);
FORCEPROP 0 LAST CDS_SEC 1
J 0
(-4450 3200);
DISPLAY 1.021277 (-4450 3200);
DISPLAY INVISIBLE (-4450 3200);
FORCEPROP 1 LASTPIN (-4500 3125) $PN 1
J 0
(-4495 3087);
DISPLAY 0.787234 (-4495 3087);
PAINT MONO (-4495 3087);
FORCEPROP 1 LASTPIN (-4500 2925) $PN 2
J 0
(-4495 2935);
DISPLAY 0.787234 (-4495 2935);
PAINT MONO (-4495 2935);
FORCEPROP 1 LAST MATERIAL CHIP
J 0
(-4460 2950);
DISPLAY 0.638298 (-4460 2950);
FORCEPROP 1 LAST VALUE 5.11K
J 0
(-4455 3100);
DISPLAY 0.638298 (-4455 3100);
FORCEPROP 1 LAST WATTAGE 1/16W
J 0
(-4460 3000);
DISPLAY 0.638298 (-4460 3000);
FORCEPROP 1 LAST TOLERANCE 1%
J 0
(-4455 3050);
DISPLAY 0.638298 (-4455 3050);
FORCEPROP 1 LAST PACK_TYPE 0402LF
J 0
(-4460 2850);
DISPLAY 0.638298 (-4460 2850);
FORCEPROP 2 LAST CDS_LIB pure_quanta
J 0
(-4500 3025);
DISPLAY INVISIBLE (-4500 3025);
FORCEPROP 1 LAST PATH I55
J 0
(-4450 3200);
DISPLAY 0.978723 (-4450 3200);
PAINT WHITE (-4450 3200);
DISPLAY INVISIBLE (-4450 3200);
FORCEPROP 1 LAST PART_NUMBER CS25112FB04
J 0
(-4460 2900);
DISPLAY 0.638298 (-4460 2900);
DISPLAY INVISIBLE (-4460 2900);
FORCEADD Q_RES..2
(-4500 3700);
FORCEPROP 1 LAST LOCATION R8114
J 0
(-4450 3775);
DISPLAY 1.021277 (-4450 3775);
FORCEPROP 0 LAST $SEC 1
J 0
(-4450 3825);
DISPLAY 0.680851 (-4450 3825);
PAINT MONO (-4450 3825);
DISPLAY INVISIBLE (-4450 3825);
FORCEPROP 0 LAST CDS_SEC 1
J 0
(-4450 3825);
DISPLAY 1.021277 (-4450 3825);
DISPLAY INVISIBLE (-4450 3825);
FORCEPROP 1 LASTPIN (-4500 3800) $PN 1
J 0
(-4495 3762);
DISPLAY 0.787234 (-4495 3762);
PAINT MONO (-4495 3762);
FORCEPROP 1 LASTPIN (-4500 3600) $PN 2
J 0
(-4495 3610);
DISPLAY 0.787234 (-4495 3610);
PAINT MONO (-4495 3610);
FORCEPROP 1 LAST VALUE 17.8K
J 0
(-4450 3750);
DISPLAY 0.510638 (-4450 3750);
FORCEPROP 1 LAST WATTAGE 1/16W
J 0
(-4450 3700);
DISPLAY 0.510638 (-4450 3700);
FORCEPROP 1 LAST PACK_TYPE 0402LF
J 0
(-4450 3625);
DISPLAY 0.510638 (-4450 3625);
FORCEPROP 1 LAST TOLERANCE 1%
J 0
(-4450 3725);
DISPLAY 0.510638 (-4450 3725);
FORCEPROP 1 LAST MATERIAL CHIP
J 0
(-4450 3675);
DISPLAY 0.510638 (-4450 3675);
FORCEPROP 2 LAST CDS_LIB pure_quanta
J 0
(-4500 3700);
DISPLAY INVISIBLE (-4500 3700);
FORCEPROP 1 LAST PATH I56
J 0
(-4450 3875);
DISPLAY 0.978723 (-4450 3875);
PAINT WHITE (-4450 3875);
DISPLAY INVISIBLE (-4450 3875);
FORCEPROP 1 LAST PART_NUMBER CS31782FB04
J 0
(-4450 3650);
DISPLAY 0.510638 (-4450 3650);
DISPLAY INVISIBLE (-4450 3650);
FORCEADD UNIVERSAL_POWER..1
(-4500 3950);
FORCEPROP 3 LASTPIN (-4500 3900) SIG_NAME P12V_AUX\g
J 0
(-4490 3910);
DISPLAY 0.659574 (-4490 3910);
PAINT MONO (-4490 3910);
DISPLAY INVISIBLE (-4490 3910);
FORCEPROP 1 LAST HDL_POWER P12V_AUX
J 1
(-4500 4000);
DISPLAY 0.723404 (-4500 4000);
PAINT GREEN (-4500 4000);
FORCEPROP 2 LAST CDS_LIB pure_quanta_power
J 0
(-4500 3950);
DISPLAY INVISIBLE (-4500 3950);
FORCEPROP 1 LAST PATH I57
J 0
(-4450 3975);
DISPLAY 0.872340 (-4450 3975);
PAINT AQUA (-4450 3975);
DISPLAY INVISIBLE (-4450 3975);
FORCEADD UNIVERSAL_GND..1
(-4100 2750);
FORCEPROP 3 LASTPIN (-4100 2800) SIG_NAME GND\g
J 0
(-4090 2810);
DISPLAY 0.659574 (-4090 2810);
PAINT MONO (-4090 2810);
DISPLAY INVISIBLE (-4090 2810);
FORCEPROP 2 LAST CDS_LIB pure_quanta_power
J 0
(-4100 2750);
DISPLAY INVISIBLE (-4100 2750);
FORCEPROP 1 LAST HDL_POWER GND
J 1
(-4075 2675);
DISPLAY 0.872340 (-4075 2675);
PAINT GREEN (-4075 2675);
DISPLAY INVISIBLE (-4075 2675);
FORCEPROP 1 LAST PATH I58
J 0
(-4025 2750);
DISPLAY 0.872340 (-4025 2750);
PAINT AQUA (-4025 2750);
DISPLAY INVISIBLE (-4025 2750);
FORCEADD Q_CAP..1
R 2
(-4100 3025);
FORCEPROP 1 LAST LOCATION C8017
J 2
(-3900 3150);
DISPLAY 1.021277 (-3900 3150);
FORCEPROP 0 LAST $SEC 1
J 0
(-3975 3200);
DISPLAY 0.680851 (-3975 3200);
PAINT MONO (-3975 3200);
DISPLAY INVISIBLE (-3975 3200);
FORCEPROP 0 LAST CDS_SEC 1
J 0
(-3975 3200);
DISPLAY 1.021277 (-3975 3200);
DISPLAY INVISIBLE (-3975 3200);
FORCEPROP 1 LASTPIN (-4100 3125) $PN 1
J 2
(-4110 3105);
DISPLAY 0.787234 (-4110 3105);
PAINT MONO (-4110 3105);
FORCEPROP 1 LASTPIN (-4100 2925) $PN 2
J 2
(-4110 2905);
DISPLAY 0.787234 (-4110 2905);
PAINT MONO (-4110 2905);
FORCEPROP 1 LAST PACK_TYPE C0402
J 0
(-4025 2850);
DISPLAY 0.638298 (-4025 2850);
FORCEPROP 1 LAST MATERIAL EMPTY
J 0
(-4025 2925);
DISPLAY 0.638298 (-4025 2925);
PAINT RED (-4025 2925);
FORCEPROP 1 LAST VOLTAGE 50V
J 0
(-4025 3050);
DISPLAY 0.638298 (-4025 3050);
FORCEPROP 1 LAST TOLERANCE 10%
J 0
(-4025 3000);
DISPLAY 0.638298 (-4025 3000);
FORCEPROP 1 LAST VALUE 100NF
J 0
(-4025 3100);
DISPLAY 0.638298 (-4025 3100);
FORCEPROP 2 LAST CDS_LIB pure_quanta
J 0
(-4100 3025);
DISPLAY INVISIBLE (-4100 3025);
FORCEPROP 1 LAST PATH I59
J 2
(-4150 3175);
DISPLAY 0.978723 (-4150 3175);
PAINT WHITE (-4150 3175);
DISPLAY INVISIBLE (-4150 3175);
FORCEPROP 1 LAST PART_NUMBER CH4106K1B01
J 0
(-4025 2900);
DISPLAY 0.638298 (-4025 2900);
DISPLAY INVISIBLE (-4025 2900);
FORCEADD Q_FUSE..1
R 3
(-8075 5875);
FORCEPROP 1 LAST LOCATION FS1
J 2
(-7950 5775);
DISPLAY 0.723404 (-7950 5775);
PAINT GREEN (-7950 5775);
FORCEPROP 0 LAST $SEC 1
R 1
J 0
(-7900 6050);
DISPLAY 0.680851 (-7900 6050);
PAINT MONO (-7900 6050);
DISPLAY INVISIBLE (-7900 6050);
FORCEPROP 0 LAST CDS_SEC 1
R 1
J 0
(-7900 6050);
DISPLAY 1.021277 (-7900 6050);
DISPLAY INVISIBLE (-7900 6050);
FORCEPROP 0 LASTPIN (-8075 5975) $PN 1
R 1
J 0
(-8085 5985);
DISPLAY 0.680851 (-8085 5985);
PAINT MONO (-8085 5985);
FORCEPROP 0 LASTPIN (-8075 5775) $PN 2
R 1
J 2
(-8085 5765);
DISPLAY 0.680851 (-8085 5765);
PAINT MONO (-8085 5765);
FORCEPROP 2 LAST PACK_TYPE SMLF
J 2
(-7800 5825);
DISPLAY 1.021277 (-7800 5825);
FORCEPROP 2 LAST VALUE 20A/125V
J 2
(-7600 5900);
DISPLAY 1.021277 (-7600 5900);
FORCEPROP 1 LAST MATERIAL IC
J 2
(-7900 6000);
DISPLAY 0.723404 (-7900 6000);
PAINT GREEN (-7900 6000);
FORCEPROP 2 LAST CDS_LIB pure_quanta
R 1
J 2
(-8075 5875);
DISPLAY INVISIBLE (-8075 5875);
FORCEPROP 1 LAST NEEDS_NO_SIZE TRUE
R 1
J 2
(-8075 5875);
DISPLAY 0.468085 (-8075 5875);
PAINT GREEN (-8075 5875);
DISPLAY INVISIBLE (-8075 5875);
FORCEPROP 1 LAST PATH I6
R 1
J 2
(-8130 5850);
DISPLAY 0.723404 (-8130 5850);
PAINT GREEN (-8130 5850);
DISPLAY INVISIBLE (-8130 5850);
FORCEPROP 1 LAST PART_NUMBER DKK00XFU000
J 2
(-7600 5950);
DISPLAY 0.723404 (-7600 5950);
PAINT GREEN (-7600 5950);
DISPLAY INVISIBLE (-7600 5950);
FORCEADD UNIVERSAL_GND..1
(-3675 2750);
FORCEPROP 3 LASTPIN (-3675 2800) SIG_NAME GND\g
J 0
(-3665 2810);
DISPLAY 0.659574 (-3665 2810);
PAINT MONO (-3665 2810);
DISPLAY INVISIBLE (-3665 2810);
FORCEPROP 2 LAST CDS_LIB pure_quanta_power
J 0
(-3675 2750);
DISPLAY INVISIBLE (-3675 2750);
FORCEPROP 1 LAST HDL_POWER GND
J 1
(-3650 2675);
DISPLAY 0.872340 (-3650 2675);
PAINT GREEN (-3650 2675);
DISPLAY INVISIBLE (-3650 2675);
FORCEPROP 1 LAST PATH I60
J 0
(-3600 2750);
DISPLAY 0.872340 (-3600 2750);
PAINT AQUA (-3600 2750);
DISPLAY INVISIBLE (-3600 2750);
FORCEADD Q_CAP..1
R 2
(-3675 3025);
FORCEPROP 1 LAST LOCATION C8018
J 2
(-3375 3150);
DISPLAY 1.234043 (-3375 3150);
FORCEPROP 0 LAST $SEC 1
J 0
(-3550 3200);
DISPLAY 0.680851 (-3550 3200);
PAINT MONO (-3550 3200);
DISPLAY INVISIBLE (-3550 3200);
FORCEPROP 0 LAST CDS_SEC 1
J 0
(-3550 3200);
DISPLAY 1.021277 (-3550 3200);
DISPLAY INVISIBLE (-3550 3200);
FORCEPROP 1 LASTPIN (-3675 3125) $PN 1
J 2
(-3685 3105);
DISPLAY 0.787234 (-3685 3105);
PAINT MONO (-3685 3105);
FORCEPROP 1 LASTPIN (-3675 2925) $PN 2
J 2
(-3685 2905);
DISPLAY 0.787234 (-3685 2905);
PAINT MONO (-3685 2905);
FORCEPROP 1 LAST PACK_TYPE C0402
J 0
(-3600 2850);
DISPLAY 0.638298 (-3600 2850);
FORCEPROP 1 LAST TOLERANCE 10%
J 0
(-3600 3000);
DISPLAY 0.638298 (-3600 3000);
FORCEPROP 1 LAST VALUE 100NF
J 0
(-3600 3100);
DISPLAY 0.638298 (-3600 3100);
FORCEPROP 1 LAST MATERIAL EMPTY
J 0
(-3600 2925);
DISPLAY 0.638298 (-3600 2925);
PAINT RED (-3600 2925);
FORCEPROP 1 LAST VOLTAGE 50V
J 0
(-3600 3050);
DISPLAY 0.638298 (-3600 3050);
FORCEPROP 2 LAST CDS_LIB pure_quanta
J 0
(-3675 3025);
DISPLAY INVISIBLE (-3675 3025);
FORCEPROP 1 LAST PATH I61
J 2
(-3725 3175);
DISPLAY 0.978723 (-3725 3175);
PAINT WHITE (-3725 3175);
DISPLAY INVISIBLE (-3725 3175);
FORCEPROP 1 LAST PART_NUMBER CH4106K1B01
J 0
(-3600 2900);
DISPLAY 0.638298 (-3600 2900);
DISPLAY INVISIBLE (-3600 2900);
FORCEADD UNIVERSAL_GND..1
(-3325 3000);
FORCEPROP 3 LASTPIN (-3325 3050) SIG_NAME GND\g
J 0
(-3315 3060);
DISPLAY 0.659574 (-3315 3060);
PAINT MONO (-3315 3060);
DISPLAY INVISIBLE (-3315 3060);
FORCEPROP 2 LAST CDS_LIB pure_quanta_power
J 0
(-3325 3000);
DISPLAY INVISIBLE (-3325 3000);
FORCEPROP 1 LAST HDL_POWER GND
J 1
(-3300 2925);
DISPLAY 0.872340 (-3300 2925);
PAINT GREEN (-3300 2925);
DISPLAY INVISIBLE (-3300 2925);
FORCEPROP 1 LAST PATH I62
J 0
(-3250 3000);
DISPLAY 0.872340 (-3250 3000);
PAINT AQUA (-3250 3000);
DISPLAY INVISIBLE (-3250 3000);
FORCEADD Q_RES..1
(-2875 3750);
FORCEPROP 1 LAST LOCATION R8117
J 0
(-3025 3675);
DISPLAY 0.808511 (-3025 3675);
FORCEPROP 0 LAST $SEC 1
J 0
(-3000 3850);
DISPLAY 0.680851 (-3000 3850);
PAINT MONO (-3000 3850);
DISPLAY INVISIBLE (-3000 3850);
FORCEPROP 0 LAST CDS_SEC 1
J 0
(-3000 3850);
DISPLAY 1.021277 (-3000 3850);
DISPLAY INVISIBLE (-3000 3850);
FORCEPROP 1 LASTPIN (-2975 3750) $PN 1
J 0
(-2963 3762);
DISPLAY 0.787234 (-2963 3762);
PAINT MONO (-2963 3762);
FORCEPROP 1 LASTPIN (-2775 3750) $PN 2
J 0
(-2813 3762);
DISPLAY 0.787234 (-2813 3762);
PAINT MONO (-2813 3762);
FORCEPROP 1 LAST MATERIAL CHIP
J 0
(-2750 3750);
DISPLAY 0.638298 (-2750 3750);
FORCEPROP 1 LAST VALUE 1M
J 2
(-2450 3750);
DISPLAY 0.638298 (-2450 3750);
FORCEPROP 1 LAST TOLERANCE 1%
J 0
(-2600 3750);
DISPLAY 0.638298 (-2600 3750);
FORCEPROP 1 LAST WATTAGE 1/16W
J 2
(-2275 3750);
DISPLAY 0.638298 (-2275 3750);
FORCEPROP 1 LAST PACK_TYPE 0402LF
J 0
(-2250 3750);
DISPLAY 0.638298 (-2250 3750);
FORCEPROP 2 LAST CDS_LIB pure_quanta
J 0
(-2875 3750);
DISPLAY INVISIBLE (-2875 3750);
FORCEPROP 1 LAST PATH I63
J 0
(-2925 3900);
DISPLAY 0.978723 (-2925 3900);
PAINT WHITE (-2925 3900);
DISPLAY INVISIBLE (-2925 3900);
FORCEPROP 1 LAST PART_NUMBER CS51002FB05
J 0
(-3000 3800);
DISPLAY 0.638298 (-3000 3800);
DISPLAY INVISIBLE (-3000 3800);
FORCEADD UNIVERSAL_POWER..1
(-3325 4275);
FORCEPROP 3 LASTPIN (-3325 4225) SIG_NAME P12V_AUX\g
J 0
(-3315 4235);
DISPLAY 0.659574 (-3315 4235);
PAINT MONO (-3315 4235);
DISPLAY INVISIBLE (-3315 4235);
FORCEPROP 1 LAST HDL_POWER P12V_AUX
J 1
(-3325 4325);
DISPLAY 0.723404 (-3325 4325);
PAINT GREEN (-3325 4325);
FORCEPROP 2 LAST CDS_LIB pure_quanta_power
J 0
(-3325 4275);
DISPLAY INVISIBLE (-3325 4275);
FORCEPROP 1 LAST PATH I64
J 0
(-3275 4300);
DISPLAY 0.872340 (-3275 4300);
PAINT AQUA (-3275 4300);
DISPLAY INVISIBLE (-3275 4300);
FORCEADD UNIVERSAL_GND..1
(-3075 3850);
FORCEPROP 3 LASTPIN (-3075 3900) SIG_NAME GND\g
J 0
(-3065 3910);
DISPLAY 0.659574 (-3065 3910);
PAINT MONO (-3065 3910);
DISPLAY INVISIBLE (-3065 3910);
FORCEPROP 2 LAST CDS_LIB pure_quanta_power
J 0
(-3075 3850);
DISPLAY INVISIBLE (-3075 3850);
FORCEPROP 1 LAST HDL_POWER GND
J 1
(-3050 3775);
DISPLAY 0.872340 (-3050 3775);
PAINT GREEN (-3050 3775);
DISPLAY INVISIBLE (-3050 3775);
FORCEPROP 1 LAST PATH I65
J 0
(-3000 3850);
DISPLAY 0.872340 (-3000 3850);
PAINT AQUA (-3000 3850);
DISPLAY INVISIBLE (-3000 3850);
FORCEADD Q_CAP..1
R 2
(-3075 4050);
FORCEPROP 1 LAST LOCATION C8019
J 0
(-3000 4175);
DISPLAY 0.787234 (-3000 4175);
FORCEPROP 0 LAST $SEC 1
J 0
(-3000 4225);
DISPLAY 0.680851 (-3000 4225);
PAINT MONO (-3000 4225);
DISPLAY INVISIBLE (-3000 4225);
FORCEPROP 0 LAST CDS_SEC 1
J 0
(-3000 4225);
DISPLAY 1.021277 (-3000 4225);
DISPLAY INVISIBLE (-3000 4225);
FORCEPROP 1 LASTPIN (-3075 4150) $PN 1
J 2
(-3085 4130);
DISPLAY 0.787234 (-3085 4130);
PAINT MONO (-3085 4130);
FORCEPROP 1 LASTPIN (-3075 3950) $PN 2
J 2
(-3085 3930);
DISPLAY 0.787234 (-3085 3930);
PAINT MONO (-3085 3930);
FORCEPROP 1 LAST VOLTAGE 50V
J 0
(-3000 4075);
DISPLAY 0.787234 (-3000 4075);
FORCEPROP 1 LAST VALUE 100NF
J 0
(-3000 4125);
DISPLAY 0.787234 (-3000 4125);
FORCEPROP 1 LAST TOLERANCE 10%
J 0
(-3000 4025);
DISPLAY 0.787234 (-3000 4025);
FORCEPROP 1 LAST MATERIAL X7R
J 0
(-3000 3975);
DISPLAY 0.787234 (-3000 3975);
FORCEPROP 1 LAST PACK_TYPE C0402
J 0
(-3000 3875);
DISPLAY 0.787234 (-3000 3875);
FORCEPROP 2 LAST CDS_LIB pure_quanta
J 0
(-3075 4050);
DISPLAY INVISIBLE (-3075 4050);
FORCEPROP 1 LAST PATH I66
J 2
(-3125 4200);
DISPLAY 0.978723 (-3125 4200);
PAINT WHITE (-3125 4200);
DISPLAY INVISIBLE (-3125 4200);
FORCEPROP 1 LAST PART_NUMBER CH4106K1B01
J 0
(-3000 3925);
DISPLAY 0.787234 (-3000 3925);
DISPLAY INVISIBLE (-3000 3925);
FORCEADD Q_RES..1
(-1950 3425);
FORCEPROP 1 LAST LOCATION R8118
J 0
(-2225 3425);
DISPLAY 0.978723 (-2225 3425);
FORCEPROP 0 LAST $SEC 1
J 0
(-2100 3475);
DISPLAY 0.680851 (-2100 3475);
PAINT MONO (-2100 3475);
DISPLAY INVISIBLE (-2100 3475);
FORCEPROP 0 LAST CDS_SEC 1
J 0
(-2100 3475);
DISPLAY 1.021277 (-2100 3475);
DISPLAY INVISIBLE (-2100 3475);
FORCEPROP 1 LASTPIN (-2050 3425) $PN 1
J 0
(-2038 3437);
DISPLAY 0.787234 (-2038 3437);
PAINT MONO (-2038 3437);
FORCEPROP 1 LASTPIN (-1850 3425) $PN 2
J 0
(-1888 3437);
DISPLAY 0.787234 (-1888 3437);
PAINT MONO (-1888 3437);
FORCEPROP 1 LAST TOLERANCE 1%
J 0
(-1725 3425);
DISPLAY 0.510638 (-1725 3425);
FORCEPROP 1 LAST VALUE 33.2
J 2
(-1750 3425);
DISPLAY 0.510638 (-1750 3425);
FORCEPROP 1 LAST MATERIAL CHIP
J 0
(-2150 3375);
DISPLAY 0.808511 (-2150 3375);
FORCEPROP 1 LAST PACK_TYPE 0402LF
J 0
(-1950 3525);
DISPLAY 0.404255 (-1950 3525);
DISPLAY INVISIBLE (-1950 3525);
FORCEPROP 1 LAST WATTAGE 1/16W
J 2
(-1725 3525);
DISPLAY 0.404255 (-1725 3525);
DISPLAY INVISIBLE (-1725 3525);
FORCEPROP 2 LAST CDS_LIB pure_quanta
J 0
(-1950 3425);
DISPLAY INVISIBLE (-1950 3425);
FORCEPROP 1 LAST PATH I67
J 0
(-2000 3575);
DISPLAY 0.978723 (-2000 3575);
PAINT WHITE (-2000 3575);
DISPLAY INVISIBLE (-2000 3575);
FORCEPROP 1 LAST PART_NUMBER CS03322FB03
J 0
(-2050 3500);
DISPLAY 0.404255 (-2050 3500);
DISPLAY INVISIBLE (-2050 3500);
FORCEADD OFFPAGE..2
(-825 3425);
FORCEPROP 2 LAST $XR1 80 
J 0
(-516 3425);
DISPLAY 0.638298 (-516 3425);
PAINT MONO (-516 3425);
FORCEPROP 2 LAST $XR0 269 
J 0
(-636 3425);
DISPLAY 0.638298 (-636 3425);
PAINT MONO (-636 3425);
FORCEPROP 2 LAST CDS_LIB standard
J 0
(-825 3425);
DISPLAY INVISIBLE (-825 3425);
FORCEPROP 1 LAST OFFPAGE TRUE
J 0
(-500 3300);
DISPLAY 0.872340 (-500 3300);
PAINT AQUA (-500 3300);
DISPLAY INVISIBLE (-500 3300);
FORCEPROP 1 LAST COMMENT_BODY TRUE
J 0
(-870 3330);
DISPLAY 0.872340 (-870 3330);
PAINT GREEN (-870 3330);
DISPLAY INVISIBLE (-870 3330);
FORCEPROP 2 LAST PATH I68
J 0
(-500 3475);
DISPLAY 0.680851 (-500 3475);
DISPLAY INVISIBLE (-500 3475);
FORCEADD Q_RES..2
(-975 3700);
FORCEPROP 1 LAST LOCATION R8119
J 0
(-930 3825);
DISPLAY 0.978723 (-930 3825);
FORCEPROP 0 LAST $SEC 1
J 0
(-925 3875);
DISPLAY 0.680851 (-925 3875);
PAINT MONO (-925 3875);
DISPLAY INVISIBLE (-925 3875);
FORCEPROP 0 LAST CDS_SEC 1
J 0
(-925 3875);
DISPLAY 1.021277 (-925 3875);
DISPLAY INVISIBLE (-925 3875);
FORCEPROP 1 LASTPIN (-975 3800) $PN 1
J 0
(-970 3762);
DISPLAY 0.787234 (-970 3762);
PAINT MONO (-970 3762);
FORCEPROP 1 LASTPIN (-975 3600) $PN 2
J 0
(-970 3610);
DISPLAY 0.787234 (-970 3610);
PAINT MONO (-970 3610);
FORCEPROP 1 LAST VALUE 1K
J 0
(-930 3775);
DISPLAY 0.723404 (-930 3775);
FORCEPROP 1 LAST TOLERANCE 1%
J 0
(-930 3725);
DISPLAY 0.723404 (-930 3725);
FORCEPROP 1 LAST WATTAGE 1/16W
J 0
(-935 3675);
DISPLAY 0.723404 (-935 3675);
FORCEPROP 1 LAST PACK_TYPE 0402LF
J 0
(-925 3575);
DISPLAY 0.723404 (-925 3575);
FORCEPROP 1 LAST MATERIAL CHIP
J 0
(-935 3625);
DISPLAY 0.723404 (-935 3625);
FORCEPROP 2 LAST CDS_LIB pure_quanta
J 0
(-975 3700);
DISPLAY INVISIBLE (-975 3700);
FORCEPROP 1 LAST PATH I69
J 0
(-925 3875);
DISPLAY 0.978723 (-925 3875);
PAINT WHITE (-925 3875);
DISPLAY INVISIBLE (-925 3875);
FORCEPROP 1 LAST PART_NUMBER CS21002FB06
J 0
(-935 3575);
DISPLAY 0.723404 (-935 3575);
PAINT WHITE (-935 3575);
DISPLAY INVISIBLE (-935 3575);
FORCEADD UNIVERSAL_GND..1
(-8650 325);
FORCEPROP 3 LASTPIN (-8650 375) SIG_NAME GND\g
J 0
(-8640 385);
DISPLAY 0.659574 (-8640 385);
PAINT MONO (-8640 385);
DISPLAY INVISIBLE (-8640 385);
FORCEPROP 2 LAST CDS_LIB pure_quanta_power
J 0
(-8650 325);
DISPLAY INVISIBLE (-8650 325);
FORCEPROP 1 LAST HDL_POWER GND
J 1
(-8625 250);
DISPLAY 0.872340 (-8625 250);
PAINT GREEN (-8625 250);
DISPLAY INVISIBLE (-8625 250);
FORCEPROP 1 LAST PATH I7
J 0
(-8575 325);
DISPLAY 0.872340 (-8575 325);
PAINT AQUA (-8575 325);
DISPLAY INVISIBLE (-8575 325);
FORCEADD UNIVERSAL_POWER..1
(-975 4025);
FORCEPROP 3 LASTPIN (-975 3975) SIG_NAME P3V3_AUX\g
J 0
(-965 3985);
DISPLAY 0.659574 (-965 3985);
PAINT MONO (-965 3985);
DISPLAY INVISIBLE (-965 3985);
FORCEPROP 1 LAST HDL_POWER P3V3_AUX
J 1
(-975 4075);
DISPLAY 0.723404 (-975 4075);
PAINT GREEN (-975 4075);
FORCEPROP 2 LAST CDS_LIB pure_quanta_power
J 0
(-975 4025);
DISPLAY INVISIBLE (-975 4025);
FORCEPROP 1 LAST PATH I70
J 0
(-925 4050);
DISPLAY 0.872340 (-925 4050);
PAINT AQUA (-925 4050);
DISPLAY INVISIBLE (-925 4050);
FORCEADD AP331AWG7..1
(-3325 3425);
FORCEPROP 1 LAST LOCATION U8008
J 0
(-3219 3281);
DISPLAY 0.723404 (-3219 3281);
PAINT GREEN (-3219 3281);
FORCEPROP 0 LAST $SEC 1
J 0
(-3200 3425);
DISPLAY 0.680851 (-3200 3425);
PAINT MONO (-3200 3425);
DISPLAY INVISIBLE (-3200 3425);
FORCEPROP 0 LAST CDS_SEC 1
J 0
(-3200 3425);
DISPLAY 1.021277 (-3200 3425);
DISPLAY INVISIBLE (-3200 3425);
FORCEPROP 0 LASTPIN (-3325 3175) $PN 2
R 1
J 2
(-3335 3165);
DISPLAY 0.680851 (-3335 3165);
PAINT MONO (-3335 3165);
FORCEPROP 0 LASTPIN (-3575 3475) $PN 3
J 2
(-3585 3485);
DISPLAY 0.680851 (-3585 3485);
PAINT MONO (-3585 3485);
FORCEPROP 0 LASTPIN (-3575 3375) $PN 1
J 2
(-3585 3385);
DISPLAY 0.680851 (-3585 3385);
PAINT MONO (-3585 3385);
FORCEPROP 0 LASTPIN (-3075 3425) $PN 4
J 0
(-3065 3435);
DISPLAY 0.680851 (-3065 3435);
PAINT MONO (-3065 3435);
FORCEPROP 0 LASTPIN (-3325 3675) $PN 5
R 1
J 0
(-3335 3685);
DISPLAY 0.680851 (-3335 3685);
PAINT MONO (-3335 3685);
FORCEPROP 2 LAST PART_TYPE SMLF
J 0
(-3200 3375);
DISPLAY 1.021277 (-3200 3375);
FORCEPROP 2 LAST VALUE AP331AWG-7
J 0
(-3200 3325);
DISPLAY 1.021277 (-3200 3325);
FORCEPROP 1 LAST MATERIAL IC
J 0
(-3225 3175);
DISPLAY 0.723404 (-3225 3175);
PAINT GREEN (-3225 3175);
FORCEPROP 1 LAST CDS_LMAN_SYM_OUTLINE -100,100,100,-100
J 0
(-3325 3425);
DISPLAY 0.468085 (-3325 3425);
PAINT GREEN (-3325 3425);
DISPLAY INVISIBLE (-3325 3425);
FORCEPROP 1 LAST NEEDS_NO_SIZE TRUE
J 0
(-3325 3425);
DISPLAY 0.723404 (-3325 3425);
PAINT GREEN (-3325 3425);
DISPLAY INVISIBLE (-3325 3425);
FORCEPROP 2 LAST CDS_LIB pure_quanta
J 0
(-3325 3425);
DISPLAY INVISIBLE (-3325 3425);
FORCEPROP 1 LAST PATH I71
J 0
(-3325 3425);
DISPLAY 0.723404 (-3325 3425);
PAINT GREEN (-3325 3425);
DISPLAY INVISIBLE (-3325 3425);
FORCEPROP 1 LAST PART_NUMBER AL000331011
J 0
(-3219 3234);
DISPLAY 0.723404 (-3219 3234);
PAINT GREEN (-3219 3234);
DISPLAY INVISIBLE (-3219 3234);
FORCEADD Q_RES..2
(-5175 1950);
FORCEPROP 1 LAST LOCATION R8120
J 0
(-5130 2075);
DISPLAY 0.978723 (-5130 2075);
FORCEPROP 0 LAST $SEC 1
J 0
(-5125 2125);
DISPLAY 0.680851 (-5125 2125);
PAINT MONO (-5125 2125);
DISPLAY INVISIBLE (-5125 2125);
FORCEPROP 0 LAST CDS_SEC 1
J 0
(-5125 2125);
DISPLAY 1.021277 (-5125 2125);
DISPLAY INVISIBLE (-5125 2125);
FORCEPROP 1 LASTPIN (-5175 2050) $PN 1
J 0
(-5170 2012);
DISPLAY 0.787234 (-5170 2012);
PAINT MONO (-5170 2012);
FORCEPROP 1 LASTPIN (-5175 1850) $PN 2
J 0
(-5170 1860);
DISPLAY 0.787234 (-5170 1860);
PAINT MONO (-5170 1860);
FORCEPROP 1 LAST PACK_TYPE 0402LF
J 0
(-5125 1825);
DISPLAY 0.723404 (-5125 1825);
FORCEPROP 1 LAST VALUE 10K
J 0
(-5130 2025);
DISPLAY 0.723404 (-5130 2025);
FORCEPROP 1 LAST TOLERANCE 1%
J 0
(-5130 1975);
DISPLAY 0.723404 (-5130 1975);
FORCEPROP 1 LAST MATERIAL CHIP
J 0
(-5135 1875);
DISPLAY 0.723404 (-5135 1875);
FORCEPROP 1 LAST WATTAGE 1/16W
J 0
(-5135 1925);
DISPLAY 0.723404 (-5135 1925);
FORCEPROP 2 LAST CDS_LIB pure_quanta
J 0
(-5175 1950);
DISPLAY INVISIBLE (-5175 1950);
FORCEPROP 1 LAST PATH I72
J 0
(-5125 2125);
DISPLAY 0.978723 (-5125 2125);
PAINT WHITE (-5125 2125);
DISPLAY INVISIBLE (-5125 2125);
FORCEPROP 1 LAST PART_NUMBER CS31002FB08
J 0
(-5135 1825);
DISPLAY 0.723404 (-5135 1825);
PAINT WHITE (-5135 1825);
DISPLAY INVISIBLE (-5135 1825);
FORCEADD UNIVERSAL_POWER..1
(-5175 2275);
FORCEPROP 3 LASTPIN (-5175 2225) SIG_NAME P3V3_AUX\g
J 0
(-5165 2235);
DISPLAY 0.659574 (-5165 2235);
PAINT MONO (-5165 2235);
DISPLAY INVISIBLE (-5165 2235);
FORCEPROP 1 LAST HDL_POWER P3V3_AUX
J 1
(-5175 2325);
DISPLAY 0.723404 (-5175 2325);
PAINT GREEN (-5175 2325);
FORCEPROP 2 LAST CDS_LIB pure_quanta_power
J 0
(-5175 2275);
DISPLAY INVISIBLE (-5175 2275);
FORCEPROP 1 LAST PATH I73
J 0
(-5125 2300);
DISPLAY 0.872340 (-5125 2300);
PAINT AQUA (-5125 2300);
DISPLAY INVISIBLE (-5125 2300);
FORCEADD UNIVERSAL_GND..1
(-4175 1050);
FORCEPROP 3 LASTPIN (-4175 1100) SIG_NAME GND\g
J 0
(-4165 1110);
DISPLAY 0.659574 (-4165 1110);
PAINT MONO (-4165 1110);
DISPLAY INVISIBLE (-4165 1110);
FORCEPROP 2 LAST CDS_LIB pure_quanta_power
J 0
(-4175 1050);
DISPLAY INVISIBLE (-4175 1050);
FORCEPROP 1 LAST HDL_POWER GND
J 1
(-4150 975);
DISPLAY 0.872340 (-4150 975);
PAINT GREEN (-4150 975);
DISPLAY INVISIBLE (-4150 975);
FORCEPROP 1 LAST PATH I74
J 0
(-4100 1050);
DISPLAY 0.872340 (-4100 1050);
PAINT AQUA (-4100 1050);
DISPLAY INVISIBLE (-4100 1050);
FORCEADD Q_RES..2
(-4175 1325);
FORCEPROP 1 LAST LOCATION R8122
J 0
(-4150 1450);
DISPLAY 1.021277 (-4150 1450);
FORCEPROP 0 LAST $SEC 1
J 0
(-4125 1500);
DISPLAY 0.680851 (-4125 1500);
PAINT MONO (-4125 1500);
DISPLAY INVISIBLE (-4125 1500);
FORCEPROP 0 LAST CDS_SEC 1
J 0
(-4125 1500);
DISPLAY 1.021277 (-4125 1500);
DISPLAY INVISIBLE (-4125 1500);
FORCEPROP 1 LASTPIN (-4175 1425) $PN 1
J 0
(-4170 1387);
DISPLAY 0.787234 (-4170 1387);
PAINT MONO (-4170 1387);
FORCEPROP 1 LASTPIN (-4175 1225) $PN 2
J 0
(-4170 1235);
DISPLAY 0.787234 (-4170 1235);
PAINT MONO (-4170 1235);
FORCEPROP 1 LAST WATTAGE 1/16W
J 0
(-4135 1300);
DISPLAY 0.638298 (-4135 1300);
FORCEPROP 1 LAST TOLERANCE 1%
J 0
(-4130 1350);
DISPLAY 0.638298 (-4130 1350);
FORCEPROP 1 LAST VALUE 5.11K
J 0
(-4130 1400);
DISPLAY 0.638298 (-4130 1400);
FORCEPROP 1 LAST PACK_TYPE 0402LF
J 0
(-4135 1150);
DISPLAY 0.638298 (-4135 1150);
FORCEPROP 1 LAST MATERIAL CHIP
J 0
(-4135 1250);
DISPLAY 0.638298 (-4135 1250);
FORCEPROP 2 LAST CDS_LIB pure_quanta
J 0
(-4175 1325);
DISPLAY INVISIBLE (-4175 1325);
FORCEPROP 1 LAST PATH I75
J 0
(-4125 1500);
DISPLAY 0.978723 (-4125 1500);
PAINT WHITE (-4125 1500);
DISPLAY INVISIBLE (-4125 1500);
FORCEPROP 1 LAST PART_NUMBER CS25112FB04
J 0
(-4135 1200);
DISPLAY 0.638298 (-4135 1200);
DISPLAY INVISIBLE (-4135 1200);
FORCEADD Q_RES..2
(-4175 2000);
FORCEPROP 1 LAST LOCATION R8121
J 0
(-4125 2175);
DISPLAY 1.021277 (-4125 2175);
FORCEPROP 0 LAST $SEC 1
J 0
(-4125 2125);
DISPLAY 0.680851 (-4125 2125);
PAINT MONO (-4125 2125);
DISPLAY INVISIBLE (-4125 2125);
FORCEPROP 0 LAST CDS_SEC 1
J 0
(-4125 2125);
DISPLAY 1.021277 (-4125 2125);
DISPLAY INVISIBLE (-4125 2125);
FORCEPROP 1 LASTPIN (-4175 2100) $PN 1
J 0
(-4170 2062);
DISPLAY 0.787234 (-4170 2062);
PAINT MONO (-4170 2062);
FORCEPROP 1 LASTPIN (-4175 1900) $PN 2
J 0
(-4170 1910);
DISPLAY 0.787234 (-4170 1910);
PAINT MONO (-4170 1910);
FORCEPROP 1 LAST PACK_TYPE 0402LF
J 0
(-4125 1875);
DISPLAY 0.638298 (-4125 1875);
FORCEPROP 1 LAST MATERIAL CHIP
J 0
(-4125 1975);
DISPLAY 0.638298 (-4125 1975);
FORCEPROP 1 LAST WATTAGE 1/16W
J 0
(-4125 2025);
DISPLAY 0.638298 (-4125 2025);
FORCEPROP 1 LAST TOLERANCE 1%
J 0
(-4125 2075);
DISPLAY 0.638298 (-4125 2075);
FORCEPROP 1 LAST VALUE 17.8K
J 0
(-4125 2125);
DISPLAY 0.638298 (-4125 2125);
FORCEPROP 2 LAST CDS_LIB pure_quanta
J 0
(-4175 2000);
DISPLAY INVISIBLE (-4175 2000);
FORCEPROP 1 LAST PATH I76
J 0
(-4125 2175);
DISPLAY 0.978723 (-4125 2175);
PAINT WHITE (-4125 2175);
DISPLAY INVISIBLE (-4125 2175);
FORCEPROP 1 LAST PART_NUMBER CS31782FB04
J 0
(-4125 1925);
DISPLAY 0.638298 (-4125 1925);
DISPLAY INVISIBLE (-4125 1925);
FORCEADD UNIVERSAL_POWER..1
(-4175 2250);
FORCEPROP 3 LASTPIN (-4175 2200) SIG_NAME P12V_AUX\g
J 0
(-4165 2210);
DISPLAY 0.659574 (-4165 2210);
PAINT MONO (-4165 2210);
DISPLAY INVISIBLE (-4165 2210);
FORCEPROP 1 LAST HDL_POWER P12V_AUX
J 1
(-4175 2300);
DISPLAY 0.723404 (-4175 2300);
PAINT GREEN (-4175 2300);
FORCEPROP 2 LAST CDS_LIB pure_quanta_power
J 0
(-4175 2250);
DISPLAY INVISIBLE (-4175 2250);
FORCEPROP 1 LAST PATH I77
J 0
(-4125 2275);
DISPLAY 0.872340 (-4125 2275);
PAINT AQUA (-4125 2275);
DISPLAY INVISIBLE (-4125 2275);
FORCEADD UNIVERSAL_GND..1
(-3775 1050);
FORCEPROP 3 LASTPIN (-3775 1100) SIG_NAME GND\g
J 0
(-3765 1110);
DISPLAY 0.659574 (-3765 1110);
PAINT MONO (-3765 1110);
DISPLAY INVISIBLE (-3765 1110);
FORCEPROP 2 LAST CDS_LIB pure_quanta_power
J 0
(-3775 1050);
DISPLAY INVISIBLE (-3775 1050);
FORCEPROP 1 LAST HDL_POWER GND
J 1
(-3750 975);
DISPLAY 0.872340 (-3750 975);
PAINT GREEN (-3750 975);
DISPLAY INVISIBLE (-3750 975);
FORCEPROP 1 LAST PATH I78
J 0
(-3700 1050);
DISPLAY 0.872340 (-3700 1050);
PAINT AQUA (-3700 1050);
DISPLAY INVISIBLE (-3700 1050);
FORCEADD Q_CAP..1
R 2
(-3775 1325);
FORCEPROP 1 LAST LOCATION C8020
J 2
(-3550 1450);
DISPLAY 0.787234 (-3550 1450);
FORCEPROP 0 LAST $SEC 1
J 0
(-3650 1500);
DISPLAY 0.680851 (-3650 1500);
PAINT MONO (-3650 1500);
DISPLAY INVISIBLE (-3650 1500);
FORCEPROP 0 LAST CDS_SEC 1
J 0
(-3650 1500);
DISPLAY 1.021277 (-3650 1500);
DISPLAY INVISIBLE (-3650 1500);
FORCEPROP 1 LASTPIN (-3775 1425) $PN 1
J 2
(-3785 1405);
DISPLAY 0.787234 (-3785 1405);
PAINT MONO (-3785 1405);
FORCEPROP 1 LASTPIN (-3775 1225) $PN 2
J 2
(-3785 1205);
DISPLAY 0.787234 (-3785 1205);
PAINT MONO (-3785 1205);
FORCEPROP 1 LAST TOLERANCE 10%
J 0
(-3700 1300);
DISPLAY 0.638298 (-3700 1300);
FORCEPROP 1 LAST MATERIAL EMPTY
J 0
(-3700 1225);
DISPLAY 0.638298 (-3700 1225);
PAINT RED (-3700 1225);
FORCEPROP 1 LAST VOLTAGE 50V
J 0
(-3700 1350);
DISPLAY 0.638298 (-3700 1350);
FORCEPROP 1 LAST VALUE 100NF
J 0
(-3700 1400);
DISPLAY 0.638298 (-3700 1400);
FORCEPROP 1 LAST PACK_TYPE C0402
J 0
(-3700 1150);
DISPLAY 0.638298 (-3700 1150);
FORCEPROP 2 LAST CDS_LIB pure_quanta
J 0
(-3775 1325);
DISPLAY INVISIBLE (-3775 1325);
FORCEPROP 1 LAST PATH I79
J 2
(-3825 1475);
DISPLAY 0.978723 (-3825 1475);
PAINT WHITE (-3825 1475);
DISPLAY INVISIBLE (-3825 1475);
FORCEPROP 1 LAST PART_NUMBER CH4106K1B01
J 0
(-3700 1200);
DISPLAY 0.638298 (-3700 1200);
DISPLAY INVISIBLE (-3700 1200);
FORCEADD OFFPAGE..4
R 2
(-8825 775);
FORCEPROP 2 LAST $XR0 241 
J 0
(-9107 775);
DISPLAY 0.638298 (-9107 775);
PAINT MONO (-9107 775);
FORCEPROP 2 LAST CDS_LIB standard
J 0
(-8825 775);
DISPLAY INVISIBLE (-8825 775);
FORCEPROP 1 LAST OFFPAGE TRUE
J 2
(-9150 650);
DISPLAY 0.872340 (-9150 650);
PAINT GREEN (-9150 650);
DISPLAY INVISIBLE (-9150 650);
FORCEPROP 1 LAST COMMENT_BODY TRUE
J 2
(-8800 675);
DISPLAY 0.872340 (-8800 675);
PAINT GREEN (-8800 675);
DISPLAY INVISIBLE (-8800 675);
FORCEPROP 2 LAST PATH I8
J 0
(-9075 825);
DISPLAY 0.680851 (-9075 825);
DISPLAY INVISIBLE (-9075 825);
FORCEADD AP331AWG7..1
(-3000 1725);
FORCEPROP 1 LAST LOCATION U8010
J 0
(-2894 1581);
DISPLAY 0.723404 (-2894 1581);
PAINT GREEN (-2894 1581);
FORCEPROP 0 LAST $SEC 1
J 0
(-2875 1725);
DISPLAY 0.680851 (-2875 1725);
PAINT MONO (-2875 1725);
DISPLAY INVISIBLE (-2875 1725);
FORCEPROP 0 LAST CDS_SEC 1
J 0
(-2875 1725);
DISPLAY 1.021277 (-2875 1725);
DISPLAY INVISIBLE (-2875 1725);
FORCEPROP 0 LASTPIN (-3000 1475) $PN 2
R 1
J 2
(-3010 1465);
DISPLAY 0.680851 (-3010 1465);
PAINT MONO (-3010 1465);
FORCEPROP 0 LASTPIN (-3250 1775) $PN 3
J 2
(-3260 1785);
DISPLAY 0.680851 (-3260 1785);
PAINT MONO (-3260 1785);
FORCEPROP 0 LASTPIN (-3250 1675) $PN 1
J 2
(-3260 1685);
DISPLAY 0.680851 (-3260 1685);
PAINT MONO (-3260 1685);
FORCEPROP 0 LASTPIN (-2750 1725) $PN 4
J 0
(-2740 1735);
DISPLAY 0.680851 (-2740 1735);
PAINT MONO (-2740 1735);
FORCEPROP 0 LASTPIN (-3000 1975) $PN 5
R 1
J 0
(-3010 1985);
DISPLAY 0.680851 (-3010 1985);
PAINT MONO (-3010 1985);
FORCEPROP 1 LAST MATERIAL IC
J 0
(-2900 1475);
DISPLAY 0.723404 (-2900 1475);
PAINT GREEN (-2900 1475);
FORCEPROP 2 LAST VALUE AP331AWG-7
J 0
(-2875 1625);
DISPLAY 1.021277 (-2875 1625);
FORCEPROP 2 LAST PART_TYPE SMLF
J 0
(-2875 1675);
DISPLAY 1.021277 (-2875 1675);
FORCEPROP 2 LAST CDS_LIB pure_quanta
J 0
(-3000 1725);
DISPLAY INVISIBLE (-3000 1725);
FORCEPROP 1 LAST NEEDS_NO_SIZE TRUE
J 0
(-3000 1725);
DISPLAY 0.723404 (-3000 1725);
PAINT GREEN (-3000 1725);
DISPLAY INVISIBLE (-3000 1725);
FORCEPROP 1 LAST CDS_LMAN_SYM_OUTLINE -100,100,100,-100
J 0
(-3000 1725);
DISPLAY 0.468085 (-3000 1725);
PAINT GREEN (-3000 1725);
DISPLAY INVISIBLE (-3000 1725);
FORCEPROP 1 LAST PATH I80
J 0
(-3000 1725);
DISPLAY 0.723404 (-3000 1725);
PAINT GREEN (-3000 1725);
DISPLAY INVISIBLE (-3000 1725);
FORCEPROP 1 LAST PART_NUMBER AL000331011
J 0
(-2894 1534);
DISPLAY 0.723404 (-2894 1534);
PAINT GREEN (-2894 1534);
DISPLAY INVISIBLE (-2894 1534);
FORCEADD Q_RES..1
(-2550 2050);
FORCEPROP 1 LAST LOCATION R8123
J 0
(-2725 1975);
DISPLAY 1.021277 (-2725 1975);
FORCEPROP 0 LAST $SEC 1
J 0
(-2675 2150);
DISPLAY 0.680851 (-2675 2150);
PAINT MONO (-2675 2150);
DISPLAY INVISIBLE (-2675 2150);
FORCEPROP 0 LAST CDS_SEC 1
J 0
(-2675 2150);
DISPLAY 1.021277 (-2675 2150);
DISPLAY INVISIBLE (-2675 2150);
FORCEPROP 1 LASTPIN (-2650 2050) $PN 1
J 0
(-2638 2062);
DISPLAY 0.787234 (-2638 2062);
PAINT MONO (-2638 2062);
FORCEPROP 1 LASTPIN (-2450 2050) $PN 2
J 0
(-2488 2062);
DISPLAY 0.787234 (-2488 2062);
PAINT MONO (-2488 2062);
FORCEPROP 1 LAST VALUE 1M
J 2
(-2125 2050);
DISPLAY 0.638298 (-2125 2050);
FORCEPROP 1 LAST WATTAGE 1/16W
J 2
(-1950 2050);
DISPLAY 0.638298 (-1950 2050);
FORCEPROP 1 LAST PACK_TYPE 0402LF
J 0
(-1925 2050);
DISPLAY 0.638298 (-1925 2050);
FORCEPROP 1 LAST MATERIAL CHIP
J 0
(-2425 2050);
DISPLAY 0.638298 (-2425 2050);
FORCEPROP 1 LAST TOLERANCE 1%
J 0
(-2275 2050);
DISPLAY 0.638298 (-2275 2050);
FORCEPROP 2 LAST CDS_LIB pure_quanta
J 0
(-2550 2050);
DISPLAY INVISIBLE (-2550 2050);
FORCEPROP 1 LAST PATH I81
J 0
(-2600 2200);
DISPLAY 0.978723 (-2600 2200);
PAINT WHITE (-2600 2200);
DISPLAY INVISIBLE (-2600 2200);
FORCEPROP 1 LAST PART_NUMBER CS51002FB05
J 0
(-2675 2100);
DISPLAY 0.638298 (-2675 2100);
DISPLAY INVISIBLE (-2675 2100);
FORCEADD UNIVERSAL_GND..1
(-2750 2150);
FORCEPROP 3 LASTPIN (-2750 2200) SIG_NAME GND\g
J 0
(-2740 2210);
DISPLAY 0.659574 (-2740 2210);
PAINT MONO (-2740 2210);
DISPLAY INVISIBLE (-2740 2210);
FORCEPROP 2 LAST CDS_LIB pure_quanta_power
J 0
(-2750 2150);
DISPLAY INVISIBLE (-2750 2150);
FORCEPROP 1 LAST HDL_POWER GND
J 1
(-2725 2075);
DISPLAY 0.872340 (-2725 2075);
PAINT GREEN (-2725 2075);
DISPLAY INVISIBLE (-2725 2075);
FORCEPROP 1 LAST PATH I82
J 0
(-2675 2150);
DISPLAY 0.872340 (-2675 2150);
PAINT AQUA (-2675 2150);
DISPLAY INVISIBLE (-2675 2150);
FORCEADD UNIVERSAL_POWER..1
(-3000 2575);
FORCEPROP 3 LASTPIN (-3000 2525) SIG_NAME P12V_AUX\g
J 0
(-2990 2535);
DISPLAY 0.659574 (-2990 2535);
PAINT MONO (-2990 2535);
DISPLAY INVISIBLE (-2990 2535);
FORCEPROP 1 LAST HDL_POWER P12V_AUX
J 1
(-3000 2625);
DISPLAY 0.723404 (-3000 2625);
PAINT GREEN (-3000 2625);
FORCEPROP 2 LAST CDS_LIB pure_quanta_power
J 0
(-3000 2575);
DISPLAY INVISIBLE (-3000 2575);
FORCEPROP 1 LAST PATH I83
J 0
(-2950 2600);
DISPLAY 0.872340 (-2950 2600);
PAINT AQUA (-2950 2600);
DISPLAY INVISIBLE (-2950 2600);
FORCEADD Q_CAP..1
R 2
(-2750 2350);
FORCEPROP 1 LAST LOCATION C8022
J 0
(-2675 2475);
DISPLAY 0.787234 (-2675 2475);
FORCEPROP 0 LAST $SEC 1
J 0
(-2675 2525);
DISPLAY 0.680851 (-2675 2525);
PAINT MONO (-2675 2525);
DISPLAY INVISIBLE (-2675 2525);
FORCEPROP 0 LAST CDS_SEC 1
J 0
(-2675 2525);
DISPLAY 1.021277 (-2675 2525);
DISPLAY INVISIBLE (-2675 2525);
FORCEPROP 1 LASTPIN (-2750 2450) $PN 1
J 2
(-2760 2430);
DISPLAY 0.787234 (-2760 2430);
PAINT MONO (-2760 2430);
FORCEPROP 1 LASTPIN (-2750 2250) $PN 2
J 2
(-2760 2230);
DISPLAY 0.787234 (-2760 2230);
PAINT MONO (-2760 2230);
FORCEPROP 1 LAST MATERIAL X7R
J 0
(-2675 2275);
DISPLAY 0.787234 (-2675 2275);
FORCEPROP 1 LAST TOLERANCE 10%
J 0
(-2675 2325);
DISPLAY 0.787234 (-2675 2325);
FORCEPROP 1 LAST VOLTAGE 50V
J 0
(-2675 2375);
DISPLAY 0.787234 (-2675 2375);
FORCEPROP 1 LAST VALUE 100NF
J 0
(-2675 2425);
DISPLAY 0.787234 (-2675 2425);
FORCEPROP 1 LAST PACK_TYPE C0402
J 0
(-2675 2175);
DISPLAY 0.787234 (-2675 2175);
FORCEPROP 2 LAST CDS_LIB pure_quanta
J 0
(-2750 2350);
DISPLAY INVISIBLE (-2750 2350);
FORCEPROP 1 LAST PATH I84
J 2
(-2800 2500);
DISPLAY 0.978723 (-2800 2500);
PAINT WHITE (-2800 2500);
DISPLAY INVISIBLE (-2800 2500);
FORCEPROP 1 LAST PART_NUMBER CH4106K1B01
J 0
(-2675 2225);
DISPLAY 0.787234 (-2675 2225);
DISPLAY INVISIBLE (-2675 2225);
FORCEADD Q_RES..1
(-1625 1725);
FORCEPROP 1 LAST LOCATION R8124
J 0
(-1850 1725);
DISPLAY 0.787234 (-1850 1725);
FORCEPROP 0 LAST $SEC 1
J 0
(-1775 1775);
DISPLAY 0.680851 (-1775 1775);
PAINT MONO (-1775 1775);
DISPLAY INVISIBLE (-1775 1775);
FORCEPROP 0 LAST CDS_SEC 1
J 0
(-1775 1775);
DISPLAY 1.021277 (-1775 1775);
DISPLAY INVISIBLE (-1775 1775);
FORCEPROP 1 LASTPIN (-1725 1725) $PN 1
J 0
(-1713 1737);
DISPLAY 0.787234 (-1713 1737);
PAINT MONO (-1713 1737);
FORCEPROP 1 LASTPIN (-1525 1725) $PN 2
J 0
(-1563 1737);
DISPLAY 0.787234 (-1563 1737);
PAINT MONO (-1563 1737);
FORCEPROP 1 LAST TOLERANCE 1%
J 0
(-1400 1725);
DISPLAY 0.510638 (-1400 1725);
FORCEPROP 1 LAST VALUE 33.2
J 2
(-1425 1725);
DISPLAY 0.510638 (-1425 1725);
FORCEPROP 1 LAST MATERIAL CHIP
J 0
(-1725 1625);
DISPLAY 1.021277 (-1725 1625);
FORCEPROP 2 LAST CDS_LIB pure_quanta
J 0
(-1625 1725);
DISPLAY INVISIBLE (-1625 1725);
FORCEPROP 1 LAST WATTAGE 1/16W
J 2
(-1400 1825);
DISPLAY 0.404255 (-1400 1825);
DISPLAY INVISIBLE (-1400 1825);
FORCEPROP 1 LAST PACK_TYPE 0402LF
J 0
(-1625 1825);
DISPLAY 0.404255 (-1625 1825);
DISPLAY INVISIBLE (-1625 1825);
FORCEPROP 1 LAST PATH I85
J 0
(-1675 1875);
DISPLAY 0.978723 (-1675 1875);
PAINT WHITE (-1675 1875);
DISPLAY INVISIBLE (-1675 1875);
FORCEPROP 1 LAST PART_NUMBER CS03322FB03
J 0
(-1725 1800);
DISPLAY 0.404255 (-1725 1800);
DISPLAY INVISIBLE (-1725 1800);
FORCEADD OFFPAGE..2
(-500 1725);
FORCEPROP 2 LAST $XR1 80 
J 0
(-191 1725);
DISPLAY 0.638298 (-191 1725);
PAINT MONO (-191 1725);
FORCEPROP 2 LAST $XR0 269 
J 0
(-311 1725);
DISPLAY 0.638298 (-311 1725);
PAINT MONO (-311 1725);
FORCEPROP 2 LAST CDS_LIB standard
J 0
(-500 1725);
DISPLAY INVISIBLE (-500 1725);
FORCEPROP 1 LAST OFFPAGE TRUE
J 0
(-175 1600);
DISPLAY 0.872340 (-175 1600);
PAINT AQUA (-175 1600);
DISPLAY INVISIBLE (-175 1600);
FORCEPROP 1 LAST COMMENT_BODY TRUE
J 0
(-545 1630);
DISPLAY 0.872340 (-545 1630);
PAINT GREEN (-545 1630);
DISPLAY INVISIBLE (-545 1630);
FORCEPROP 2 LAST PATH I86
J 0
(-175 1775);
DISPLAY 0.680851 (-175 1775);
DISPLAY INVISIBLE (-175 1775);
FORCEADD UNIVERSAL_POWER..1
(-650 2325);
FORCEPROP 3 LASTPIN (-650 2275) SIG_NAME P3V3_AUX\g
J 0
(-640 2285);
DISPLAY 0.659574 (-640 2285);
PAINT MONO (-640 2285);
DISPLAY INVISIBLE (-640 2285);
FORCEPROP 1 LAST HDL_POWER P3V3_AUX
J 1
(-650 2375);
DISPLAY 0.723404 (-650 2375);
PAINT GREEN (-650 2375);
FORCEPROP 2 LAST CDS_LIB pure_quanta_power
J 0
(-650 2325);
DISPLAY INVISIBLE (-650 2325);
FORCEPROP 1 LAST PATH I88
J 0
(-600 2350);
DISPLAY 0.872340 (-600 2350);
PAINT AQUA (-600 2350);
DISPLAY INVISIBLE (-600 2350);
FORCEADD UNIVERSAL_GND..1
(-5150 800);
FORCEPROP 3 LASTPIN (-5150 850) SIG_NAME GND\g
J 0
(-5140 860);
DISPLAY 0.659574 (-5140 860);
PAINT MONO (-5140 860);
DISPLAY INVISIBLE (-5140 860);
FORCEPROP 2 LAST CDS_LIB pure_quanta_power
J 0
(-5150 800);
DISPLAY INVISIBLE (-5150 800);
FORCEPROP 1 LAST HDL_POWER GND
J 1
(-5125 725);
DISPLAY 0.872340 (-5125 725);
PAINT GREEN (-5125 725);
DISPLAY INVISIBLE (-5125 725);
FORCEPROP 1 LAST PATH I89
J 0
(-5075 800);
DISPLAY 0.872340 (-5075 800);
PAINT AQUA (-5075 800);
DISPLAY INVISIBLE (-5075 800);
FORCEADD Q_CAP..1
(-8650 550);
FORCEPROP 1 LAST LOCATION C1797
J 0
(-8575 650);
DISPLAY 0.978723 (-8575 650);
FORCEPROP 0 LAST $SEC 1
J 0
(-8600 700);
DISPLAY 0.680851 (-8600 700);
PAINT MONO (-8600 700);
DISPLAY INVISIBLE (-8600 700);
FORCEPROP 0 LAST CDS_SEC 1
J 0
(-8600 700);
DISPLAY 1.021277 (-8600 700);
DISPLAY INVISIBLE (-8600 700);
FORCEPROP 1 LASTPIN (-8650 650) $PN 1
J 0
(-8640 630);
DISPLAY 0.787234 (-8640 630);
PAINT MONO (-8640 630);
DISPLAY INVISIBLE (-8640 630);
FORCEPROP 1 LASTPIN (-8650 450) $PN 2
J 0
(-8640 430);
DISPLAY 0.787234 (-8640 430);
PAINT MONO (-8640 430);
DISPLAY INVISIBLE (-8640 430);
FORCEPROP 1 LAST VALUE 0.1UF
J 0
(-8575 550);
DISPLAY 0.723404 (-8575 550);
PAINT SKYBLUE (-8575 550);
FORCEPROP 1 LAST TOLERANCE 10%
J 0
(-8575 450);
DISPLAY 0.723404 (-8575 450);
PAINT SKYBLUE (-8575 450);
FORCEPROP 1 LAST VOLTAGE 25V
J 0
(-8575 500);
DISPLAY 0.723404 (-8575 500);
PAINT SKYBLUE (-8575 500);
FORCEPROP 1 LAST MATERIAL X7R
J 0
(-8575 400);
DISPLAY 0.723404 (-8575 400);
PAINT SKYBLUE (-8575 400);
FORCEPROP 1 LAST PACK_TYPE 0402
J 0
(-8575 350);
DISPLAY 0.723404 (-8575 350);
PAINT SKYBLUE (-8575 350);
FORCEPROP 2 LAST CDS_LIB pure_quanta
J 0
(-8650 550);
DISPLAY INVISIBLE (-8650 550);
FORCEPROP 1 LAST PATH I9
J 0
(-8600 700);
DISPLAY 0.978723 (-8600 700);
PAINT WHITE (-8600 700);
DISPLAY INVISIBLE (-8600 700);
FORCEPROP 1 LAST PART_NUMBER CH4104K1B00
J 0
(-8575 600);
DISPLAY 0.723404 (-8575 600);
PAINT BLUE (-8575 600);
DISPLAY INVISIBLE (-8575 600);
FORCEADD UNIVERSAL_GND..1
(-3350 1050);
FORCEPROP 3 LASTPIN (-3350 1100) SIG_NAME GND\g
J 0
(-3340 1110);
DISPLAY 0.659574 (-3340 1110);
PAINT MONO (-3340 1110);
DISPLAY INVISIBLE (-3340 1110);
FORCEPROP 2 LAST CDS_LIB pure_quanta_power
J 0
(-3350 1050);
DISPLAY INVISIBLE (-3350 1050);
FORCEPROP 1 LAST HDL_POWER GND
J 1
(-3325 975);
DISPLAY 0.872340 (-3325 975);
PAINT GREEN (-3325 975);
DISPLAY INVISIBLE (-3325 975);
FORCEPROP 1 LAST PATH I90
J 0
(-3275 1050);
DISPLAY 0.872340 (-3275 1050);
PAINT AQUA (-3275 1050);
DISPLAY INVISIBLE (-3275 1050);
FORCEADD UNIVERSAL_GND..1
(-3000 1300);
FORCEPROP 3 LASTPIN (-3000 1350) SIG_NAME GND\g
J 0
(-2990 1360);
DISPLAY 0.659574 (-2990 1360);
PAINT MONO (-2990 1360);
DISPLAY INVISIBLE (-2990 1360);
FORCEPROP 2 LAST CDS_LIB pure_quanta_power
J 0
(-3000 1300);
DISPLAY INVISIBLE (-3000 1300);
FORCEPROP 1 LAST HDL_POWER GND
J 1
(-2975 1225);
DISPLAY 0.872340 (-2975 1225);
PAINT GREEN (-2975 1225);
DISPLAY INVISIBLE (-2975 1225);
FORCEPROP 1 LAST PATH I91
J 0
(-2925 1300);
DISPLAY 0.872340 (-2925 1300);
PAINT AQUA (-2925 1300);
DISPLAY INVISIBLE (-2925 1300);
FORCEADD Q_CAP..1
R 2
(-3350 1325);
FORCEPROP 1 LAST LOCATION C8021
J 2
(-3125 1450);
DISPLAY 0.787234 (-3125 1450);
FORCEPROP 0 LAST $SEC 1
J 0
(-3225 1500);
DISPLAY 0.680851 (-3225 1500);
PAINT MONO (-3225 1500);
DISPLAY INVISIBLE (-3225 1500);
FORCEPROP 0 LAST CDS_SEC 1
J 0
(-3225 1500);
DISPLAY 1.021277 (-3225 1500);
DISPLAY INVISIBLE (-3225 1500);
FORCEPROP 1 LASTPIN (-3350 1425) $PN 1
J 2
(-3360 1405);
DISPLAY 0.787234 (-3360 1405);
PAINT MONO (-3360 1405);
FORCEPROP 1 LASTPIN (-3350 1225) $PN 2
J 2
(-3360 1205);
DISPLAY 0.787234 (-3360 1205);
PAINT MONO (-3360 1205);
FORCEPROP 1 LAST VALUE 100NF
J 0
(-3275 1400);
DISPLAY 0.638298 (-3275 1400);
FORCEPROP 1 LAST VOLTAGE 50V
J 0
(-3275 1350);
DISPLAY 0.638298 (-3275 1350);
FORCEPROP 1 LAST TOLERANCE 10%
J 0
(-3275 1300);
DISPLAY 0.638298 (-3275 1300);
FORCEPROP 1 LAST PACK_TYPE C0402
J 0
(-3275 1150);
DISPLAY 0.638298 (-3275 1150);
FORCEPROP 1 LAST MATERIAL EMPTY
J 0
(-3275 1225);
DISPLAY 0.638298 (-3275 1225);
PAINT RED (-3275 1225);
FORCEPROP 2 LAST CDS_LIB pure_quanta
J 0
(-3350 1325);
DISPLAY INVISIBLE (-3350 1325);
FORCEPROP 1 LAST PATH I92
J 2
(-3400 1475);
DISPLAY 0.978723 (-3400 1475);
PAINT WHITE (-3400 1475);
DISPLAY INVISIBLE (-3400 1475);
FORCEPROP 1 LAST PART_NUMBER CH4106K1B01
J 0
(-3275 1200);
DISPLAY 0.638298 (-3275 1200);
DISPLAY INVISIBLE (-3275 1200);
FORCEADD LM4040AIM3X25NOPB..1
(-4775 1125);
FORCEPROP 1 LAST LOCATION U8009
J 0
(-4978 1503);
DISPLAY 0.723404 (-4978 1503);
PAINT GREEN (-4978 1503);
FORCEPROP 0 LAST $SEC 1
J 0
(-4975 1650);
DISPLAY 0.680851 (-4975 1650);
PAINT MONO (-4975 1650);
DISPLAY INVISIBLE (-4975 1650);
FORCEPROP 0 LAST CDS_SEC 1
J 0
(-4975 1650);
DISPLAY 1.021277 (-4975 1650);
DISPLAY INVISIBLE (-4975 1650);
FORCEPROP 0 LASTPIN (-5125 1275) $PN 1
J 2
(-5135 1285);
DISPLAY 0.680851 (-5135 1285);
PAINT MONO (-5135 1285);
FORCEPROP 0 LASTPIN (-5125 975) $PN 2
J 2
(-5135 985);
DISPLAY 0.680851 (-5135 985);
PAINT MONO (-5135 985);
FORCEPROP 0 LASTPIN (-4425 1125) $PN 3
J 0
(-4415 1135);
DISPLAY 0.680851 (-4415 1135);
PAINT MONO (-4415 1135);
FORCEPROP 2 LAST PART_TYPE SMLF
J 0
(-4975 1600);
DISPLAY 0.808511 (-4975 1600);
FORCEPROP 1 LAST MATERIAL IC
J 0
(-4978 1380);
DISPLAY 0.723404 (-4978 1380);
PAINT GREEN (-4978 1380);
FORCEPROP 2 LAST VALUE LM4040AIM3X-2.5/NOPB
J 0
(-4975 1550);
DISPLAY 0.808511 (-4975 1550);
FORCEPROP 1 LAST CDS_LMAN_SYM_OUTLINE -200,250,200,-250
J 0
(-4775 1125);
DISPLAY 0.468085 (-4775 1125);
PAINT GREEN (-4775 1125);
DISPLAY INVISIBLE (-4775 1125);
FORCEPROP 1 LAST PIN_NAMES_ROTATE True
J 0
(-4775 1125);
DISPLAY 0.489362 (-4775 1125);
PAINT GREEN (-4775 1125);
DISPLAY INVISIBLE (-4775 1125);
FORCEPROP 2 LAST CDS_LIB pure_quanta
J 0
(-4775 1125);
DISPLAY INVISIBLE (-4775 1125);
FORCEPROP 1 LAST PATH I93
J 0
(-4775 1125);
DISPLAY 0.723404 (-4775 1125);
PAINT GREEN (-4775 1125);
DISPLAY INVISIBLE (-4775 1125);
FORCEPROP 1 LAST PART_NUMBER AL404025013
J 0
(-4978 1469);
DISPLAY 0.723404 (-4978 1469);
PAINT GREEN (-4978 1469);
DISPLAY INVISIBLE (-4978 1469);
FORCEADD UNIVERSAL_GND..1
(-5050 5300);
FORCEPROP 3 LASTPIN (-5050 5350) SIG_NAME GND\g
J 0
(-5040 5360);
DISPLAY 0.659574 (-5040 5360);
PAINT MONO (-5040 5360);
DISPLAY INVISIBLE (-5040 5360);
FORCEPROP 2 LAST CDS_LIB pure_quanta_power
J 0
(-5050 5300);
DISPLAY INVISIBLE (-5050 5300);
FORCEPROP 1 LAST HDL_POWER GND
J 1
(-5025 5225);
DISPLAY 0.872340 (-5025 5225);
PAINT GREEN (-5025 5225);
DISPLAY INVISIBLE (-5025 5225);
FORCEPROP 1 LAST PATH I95
J 0
(-4975 5300);
DISPLAY 0.872340 (-4975 5300);
PAINT AQUA (-4975 5300);
DISPLAY INVISIBLE (-4975 5300);
FORCEADD Q_CAP..1
(-5050 5550);
FORCEPROP 1 LAST LOCATION C1561
J 0
(-5000 5650);
DISPLAY 0.978723 (-5000 5650);
FORCEPROP 0 LAST $SEC 1
J 0
(-5000 5700);
DISPLAY 0.680851 (-5000 5700);
PAINT MONO (-5000 5700);
DISPLAY INVISIBLE (-5000 5700);
FORCEPROP 0 LAST CDS_SEC 1
J 0
(-5000 5700);
DISPLAY 1.021277 (-5000 5700);
DISPLAY INVISIBLE (-5000 5700);
FORCEPROP 1 LASTPIN (-5050 5650) $PN 1
J 0
(-5040 5630);
DISPLAY 0.787234 (-5040 5630);
PAINT MONO (-5040 5630);
FORCEPROP 1 LASTPIN (-5050 5450) $PN 2
J 0
(-5040 5430);
DISPLAY 0.787234 (-5040 5430);
PAINT MONO (-5040 5430);
FORCEPROP 1 LAST TOLERANCE 10%
J 0
(-5000 5500);
DISPLAY 0.510638 (-5000 5500);
FORCEPROP 1 LAST VALUE 0.1UF
J 0
(-5000 5600);
DISPLAY 0.510638 (-5000 5600);
FORCEPROP 1 LAST PACK_TYPE 0402
J 0
(-5000 5350);
DISPLAY 0.510638 (-5000 5350);
FORCEPROP 1 LAST MATERIAL EMPTY
J 0
(-5000 5450);
DISPLAY 0.510638 (-5000 5450);
PAINT RED (-5000 5450);
FORCEPROP 1 LAST VOLTAGE 25V
J 0
(-5000 5550);
DISPLAY 0.510638 (-5000 5550);
FORCEPROP 2 LAST CDS_LIB pure_quanta
J 0
(-5050 5550);
DISPLAY INVISIBLE (-5050 5550);
FORCEPROP 1 LAST PATH I96
J 0
(-5000 5700);
DISPLAY 0.978723 (-5000 5700);
PAINT WHITE (-5000 5700);
DISPLAY INVISIBLE (-5000 5700);
FORCEPROP 1 LAST PART_NUMBER CH4104K1B00
J 0
(-5000 5400);
DISPLAY 0.510638 (-5000 5400);
DISPLAY INVISIBLE (-5000 5400);
FORCEADD Q_RES..2
(-4650 5925);
FORCEPROP 1 LAST LOCATION R9021
J 0
(-4605 6050);
DISPLAY 0.723404 (-4605 6050);
PAINT AQUA (-4605 6050);
FORCEPROP 0 LAST $SEC 1
J 0
(-4600 6100);
DISPLAY 0.680851 (-4600 6100);
PAINT MONO (-4600 6100);
DISPLAY INVISIBLE (-4600 6100);
FORCEPROP 0 LAST CDS_SEC 1
J 0
(-4600 6100);
DISPLAY 0.680851 (-4600 6100);
DISPLAY INVISIBLE (-4600 6100);
FORCEPROP 1 LASTPIN (-4650 6025) $PN 1
J 0
(-4645 5987);
DISPLAY 0.787234 (-4645 5987);
PAINT MONO (-4645 5987);
FORCEPROP 1 LASTPIN (-4650 5825) $PN 2
J 0
(-4645 5835);
DISPLAY 0.787234 (-4645 5835);
PAINT MONO (-4645 5835);
FORCEPROP 1 LAST TOLERANCE 1%
J 0
(-4605 5950);
DISPLAY 0.723404 (-4605 5950);
PAINT SKYBLUE (-4605 5950);
FORCEPROP 1 LAST MATERIAL EMPTY
J 0
(-4610 5850);
DISPLAY 0.723404 (-4610 5850);
PAINT RED (-4610 5850);
FORCEPROP 1 LAST VALUE 1K
J 0
(-4605 6000);
DISPLAY 0.723404 (-4605 6000);
PAINT SKYBLUE (-4605 6000);
FORCEPROP 1 LAST WATTAGE 1/16W
J 0
(-4610 5900);
DISPLAY 0.723404 (-4610 5900);
PAINT SKYBLUE (-4610 5900);
FORCEPROP 1 LAST PACK_TYPE 0402LF
J 0
(-4600 5800);
DISPLAY 0.723404 (-4600 5800);
PAINT SKYBLUE (-4600 5800);
FORCEPROP 2 LAST CDS_LIB pure_quanta
J 0
(-4650 5925);
DISPLAY INVISIBLE (-4650 5925);
FORCEPROP 1 LAST PATH I97
J 0
(-4600 6100);
DISPLAY 0.978723 (-4600 6100);
PAINT WHITE (-4600 6100);
DISPLAY INVISIBLE (-4600 6100);
FORCEPROP 1 LAST PART_NUMBER CS21002FB06
J 0
(-4610 5800);
DISPLAY 0.723404 (-4610 5800);
PAINT WHITE (-4610 5800);
DISPLAY INVISIBLE (-4610 5800);
FORCEADD UNIVERSAL_POWER..1
(-4650 6175);
FORCEPROP 3 LASTPIN (-4650 6125) SIG_NAME P12V_AUX\g
J 0
(-4640 6135);
DISPLAY 0.659574 (-4640 6135);
PAINT MONO (-4640 6135);
DISPLAY INVISIBLE (-4640 6135);
FORCEPROP 1 LAST HDL_POWER P12V_AUX
J 1
(-4650 6225);
DISPLAY 0.723404 (-4650 6225);
PAINT GREEN (-4650 6225);
FORCEPROP 2 LAST CDS_LIB pure_quanta_power
J 0
(-4650 6175);
PAINT MONO (-4650 6175);
DISPLAY INVISIBLE (-4650 6175);
FORCEPROP 1 LAST PATH I98
J 0
(-4600 6200);
DISPLAY 0.872340 (-4600 6200);
PAINT AQUA (-4600 6200);
DISPLAY INVISIBLE (-4600 6200);
FORCEADD Q_CAP..1
R 2
(-4650 5525);
FORCEPROP 1 LAST LOCATION C9004
J 0
(-4575 5675);
DISPLAY 0.617021 (-4575 5675);
PAINT AQUA (-4575 5675);
FORCEPROP 0 LAST $SEC 1
J 0
(-4575 5725);
DISPLAY 0.680851 (-4575 5725);
PAINT MONO (-4575 5725);
DISPLAY INVISIBLE (-4575 5725);
FORCEPROP 0 LAST CDS_SEC 1
J 0
(-4575 5725);
DISPLAY 0.680851 (-4575 5725);
DISPLAY INVISIBLE (-4575 5725);
FORCEPROP 1 LASTPIN (-4650 5625) $PN 1
J 2
(-4660 5605);
DISPLAY 0.787234 (-4660 5605);
PAINT MONO (-4660 5605);
FORCEPROP 1 LASTPIN (-4650 5425) $PN 2
J 2
(-4660 5405);
DISPLAY 0.787234 (-4660 5405);
PAINT MONO (-4660 5405);
FORCEPROP 1 LAST PACK_TYPE C0402
J 0
(-4575 5350);
DISPLAY 0.617021 (-4575 5350);
PAINT SKYBLUE (-4575 5350);
FORCEPROP 1 LAST VOLTAGE 25V
J 0
(-4575 5550);
DISPLAY 0.617021 (-4575 5550);
PAINT SKYBLUE (-4575 5550);
FORCEPROP 1 LAST VALUE 1UF
J 0
(-4575 5600);
DISPLAY 0.617021 (-4575 5600);
PAINT SKYBLUE (-4575 5600);
FORCEPROP 1 LAST MATERIAL EMPTY
J 0
(-4575 5450);
DISPLAY 0.617021 (-4575 5450);
PAINT RED (-4575 5450);
FORCEPROP 1 LAST TOLERANCE 10%
J 0
(-4575 5500);
DISPLAY 0.617021 (-4575 5500);
PAINT SKYBLUE (-4575 5500);
FORCEPROP 2 LAST CDS_LIB pure_quanta
J 0
(-4650 5525);
DISPLAY INVISIBLE (-4650 5525);
FORCEPROP 1 LAST PATH I99
J 2
(-4700 5675);
DISPLAY 0.978723 (-4700 5675);
PAINT WHITE (-4700 5675);
DISPLAY INVISIBLE (-4700 5675);
FORCEPROP 1 LAST PART_NUMBER CH5104KEB02
J 0
(-4575 5400);
DISPLAY 0.617021 (-4575 5400);
PAINT BLUE (-4575 5400);
DISPLAY INVISIBLE (-4575 5400);
FORCEADD DNS..1
(-1525 5725);
PAINT RED (-1525 5725);
FORCEPROP 2 LAST CDS_LIB mstr_misc
J 0
(-1525 5725);
DISPLAY INVISIBLE (-1525 5725);
FORCEPROP 1 LAST COMMENT_BODY TRUE
R 1
J 0
(-1450 5500);
DISPLAY 0.872340 (-1450 5500);
PAINT GREEN (-1450 5500);
DISPLAY INVISIBLE (-1450 5500);
FORCEADD DNS..1
(-3150 5550);
PAINT RED (-3150 5550);
FORCEPROP 2 LAST CDS_LIB mstr_misc
J 0
(-3150 5550);
DISPLAY INVISIBLE (-3150 5550);
FORCEPROP 1 LAST COMMENT_BODY TRUE
R 1
J 0
(-3075 5325);
DISPLAY 0.872340 (-3075 5325);
PAINT GREEN (-3075 5325);
DISPLAY INVISIBLE (-3075 5325);
FORCEADD DNS..1
(-5475 4750);
PAINT RED (-5475 4750);
FORCEPROP 2 LAST CDS_LIB mstr_misc
J 0
(-5475 4750);
DISPLAY INVISIBLE (-5475 4750);
FORCEPROP 1 LAST COMMENT_BODY TRUE
R 1
J 0
(-5400 4525);
DISPLAY 0.872340 (-5400 4525);
PAINT GREEN (-5400 4525);
DISPLAY INVISIBLE (-5400 4525);
FORCEADD DNS..1
(-6150 5500);
PAINT RED (-6150 5500);
FORCEPROP 2 LAST CDS_LIB mstr_misc
J 0
(-6150 5500);
DISPLAY INVISIBLE (-6150 5500);
FORCEPROP 1 LAST COMMENT_BODY TRUE
R 1
J 0
(-6075 5275);
DISPLAY 0.872340 (-6075 5275);
PAINT GREEN (-6075 5275);
DISPLAY INVISIBLE (-6075 5275);
FORCEADD DNS..1
(-6075 4775);
PAINT RED (-6075 4775);
FORCEPROP 2 LAST CDS_LIB mstr_misc
J 0
(-6075 4775);
DISPLAY INVISIBLE (-6075 4775);
FORCEPROP 1 LAST COMMENT_BODY TRUE
R 1
J 0
(-6000 4550);
DISPLAY 0.872340 (-6000 4550);
PAINT GREEN (-6000 4550);
DISPLAY INVISIBLE (-6000 4550);
FORCEADD DNS..1
(-4100 3000);
PAINT RED (-4100 3000);
FORCEPROP 2 LAST CDS_LIB mstr_misc
J 0
(-4100 3000);
DISPLAY INVISIBLE (-4100 3000);
FORCEPROP 1 LAST COMMENT_BODY TRUE
R 1
J 0
(-4025 2775);
DISPLAY 0.872340 (-4025 2775);
PAINT GREEN (-4025 2775);
DISPLAY INVISIBLE (-4025 2775);
FORCEADD DNS..1
(-3675 3000);
PAINT RED (-3675 3000);
FORCEPROP 2 LAST CDS_LIB mstr_misc
J 0
(-3675 3000);
DISPLAY INVISIBLE (-3675 3000);
FORCEPROP 1 LAST COMMENT_BODY TRUE
R 1
J 0
(-3600 2775);
DISPLAY 0.872340 (-3600 2775);
PAINT GREEN (-3600 2775);
DISPLAY INVISIBLE (-3600 2775);
FORCEADD DNS..1
(-3775 1300);
PAINT RED (-3775 1300);
FORCEPROP 2 LAST CDS_LIB mstr_misc
J 0
(-3775 1300);
DISPLAY INVISIBLE (-3775 1300);
FORCEPROP 1 LAST COMMENT_BODY TRUE
R 1
J 0
(-3700 1075);
DISPLAY 0.872340 (-3700 1075);
PAINT GREEN (-3700 1075);
DISPLAY INVISIBLE (-3700 1075);
FORCEADD DNS..1
(-3350 1300);
PAINT RED (-3350 1300);
FORCEPROP 2 LAST CDS_LIB mstr_misc
J 0
(-3350 1300);
DISPLAY INVISIBLE (-3350 1300);
FORCEPROP 1 LAST COMMENT_BODY TRUE
R 1
J 0
(-3275 1075);
DISPLAY 0.872340 (-3275 1075);
PAINT GREEN (-3275 1075);
DISPLAY INVISIBLE (-3275 1075);
FORCEADD DNS..1
(-5525 5500);
PAINT RED (-5525 5500);
FORCEPROP 2 LAST CDS_LIB mstr_misc
J 0
(-5525 5500);
DISPLAY INVISIBLE (-5525 5500);
FORCEPROP 1 LAST COMMENT_BODY TRUE
R 1
J 0
(-5450 5275);
DISPLAY 0.872340 (-5450 5275);
PAINT GREEN (-5450 5275);
DISPLAY INVISIBLE (-5450 5275);
FORCEADD DNS..1
(-3900 5350);
PAINT RED (-3900 5350);
FORCEPROP 2 LAST CDS_LIB mstr_misc
J 0
(-3900 5350);
DISPLAY INVISIBLE (-3900 5350);
FORCEPROP 1 LAST COMMENT_BODY TRUE
R 1
J 0
(-3825 5125);
DISPLAY 0.872340 (-3825 5125);
PAINT GREEN (-3825 5125);
DISPLAY INVISIBLE (-3825 5125);
FORCEADD DNS..1
(-2850 5575);
PAINT RED (-2850 5575);
FORCEPROP 2 LAST CDS_LIB mstr_misc
J 0
(-2850 5575);
DISPLAY INVISIBLE (-2850 5575);
FORCEPROP 1 LAST COMMENT_BODY TRUE
R 1
J 0
(-2775 5350);
DISPLAY 0.872340 (-2775 5350);
PAINT GREEN (-2775 5350);
DISPLAY INVISIBLE (-2775 5350);
FORCEADD DNS..1
(-1625 5100);
PAINT RED (-1625 5100);
FORCEPROP 2 LAST CDS_LIB mstr_misc
J 0
(-1625 5100);
DISPLAY INVISIBLE (-1625 5100);
FORCEPROP 1 LAST COMMENT_BODY TRUE
R 1
J 0
(-1550 4875);
DISPLAY 0.872340 (-1550 4875);
PAINT GREEN (-1550 4875);
DISPLAY INVISIBLE (-1550 4875);
FORCEADD DNS..2
(-4650 5500);
PAINT RED (-4650 5500);
FORCEPROP 2 LAST CDS_LIB mstr_misc
J 0
(-4650 5500);
DISPLAY INVISIBLE (-4650 5500);
FORCEPROP 1 LAST COMMENT_BODY TRUE
R 1
J 0
(-4575 5275);
DISPLAY 0.872340 (-4575 5275);
PAINT GREEN (-4575 5275);
DISPLAY INVISIBLE (-4575 5275);
FORCEADD DNS..2
(-4650 5900);
PAINT RED (-4650 5900);
FORCEPROP 2 LAST CDS_LIB mstr_misc
J 0
(-4650 5900);
DISPLAY INVISIBLE (-4650 5900);
FORCEPROP 1 LAST COMMENT_BODY TRUE
R 1
J 0
(-4575 5675);
DISPLAY 0.872340 (-4575 5675);
PAINT GREEN (-4575 5675);
DISPLAY INVISIBLE (-4575 5675);
FORCEADD DNS..1
(-5025 5525);
PAINT RED (-5025 5525);
FORCEPROP 2 LAST CDS_LIB mstr_misc
J 0
(-5025 5525);
DISPLAY INVISIBLE (-5025 5525);
FORCEPROP 1 LAST COMMENT_BODY TRUE
R 1
J 0
(-4950 5300);
DISPLAY 0.872340 (-4950 5300);
PAINT GREEN (-4950 5300);
DISPLAY INVISIBLE (-4950 5300);
FORCEADD QUANTA_TITLE_BLOCK_C..1
(0 0);
FORCEPROP 0 LAST CDS_CON_LAST_MODIFIED Thu Sep 14 16:12:44 2023
J 0
(-1885 15);
DISPLAY INVISIBLE (-1885 15);
FORCEPROP 1 LAST CUSTOM_TXT_CDS <CON_LAST_MODIFIED>
J 0
(-1885 15);
DISPLAY 0.978723 (-1885 15);
FORCEPROP 2 LAST CUSTOM_TXT_CDS <XR_PAGE_TITLE>
J 0
(-7890 5250);
DISPLAY 0.638298 (-7890 5250);
PAINT PINK (-7890 5250);
DISPLAY INVISIBLE (-7890 5250);
FORCEPROP 1 LAST CUSTOM_TXT_CDS <NAME_2>
J 0
(-3175 50);
FORCEPROP 1 LAST CUSTOM_TXT_CDS <NAME_1>
J 0
(-3175 175);
FORCEPROP 1 LAST CUSTOM_TXT_CDS <Q_NUMBER>
J 0
(-1403 103);
DISPLAY 1.212766 (-1403 103);
FORCEPROP 1 LAST CUSTOM_TXT_CDS <Q_PROJ>
J 0
(-2382 102);
DISPLAY 1.212766 (-2382 102);
FORCEPROP 1 LAST CUSTOM_TXT_CDS <Q_REV>
J 0
(-184 103);
DISPLAY 1.212766 (-184 103);
FORCEPROP 1 LAST CUSTOM_TXT_CDS <CON_PAGE_NUM> OF <CON_TOTAL_PAGES>
J 0
(-446 18);
DISPLAY 0.978723 (-446 18);
FORCEPROP 1 LAST Q_TITLE HSC Shared Circuit
J 0
(-9366 26);
DISPLAY 2.446809 (-9366 26);
PAINT GREEN (-9366 26);
FORCEPROP 2 LAST CDS_LIB pure_quanta
J 0
(0 0);
DISPLAY INVISIBLE (0 0);
FORCEPROP 1 LAST CDS_LMAN_SYM_OUTLINE -9475,6775,100,-125
J 0
(0 0);
DISPLAY 0.468085 (0 0);
PAINT GREEN (0 0);
DISPLAY INVISIBLE (0 0);
FORCEPROP 2 LAST PAGE_BORDER TRUE
J 0
(-7890 5250);
DISPLAY 0.638298 (-7890 5250);
PAINT PINK (-7890 5250);
DISPLAY INVISIBLE (-7890 5250);
FORCEPROP 2 LAST CDS_XR_PAGE_TITLE CR-269 : @T6G_MB_LIB.T6G(SCH_1):PAGE269
J 0
(-7890 5250);
DISPLAY 0.638298 (-7890 5250);
PAINT PINK (-7890 5250);
DISPLAY INVISIBLE (-7890 5250);
FORCEPROP 1 LAST Q_DEPT BU9
J 1
(-3763 49);
DISPLAY 1.957447 (-3763 49);
PAINT GREEN (-3763 49);
DISPLAY INVISIBLE (-3763 49);
FORCEPROP 1 LAST COMMENT_BODY TRUE
J 0
(12 -13);
DISPLAY 0.978723 (12 -13);
PAINT GREEN (12 -13);
DISPLAY INVISIBLE (12 -13);
WIRE 16 -1 (-6925 3500)(-6925 3400);
WIRE 16 -1 (-6925 3500)(-7650 3500);
WIRE 16 -1 (-6525 800)(-6525 700);
WIRE 16 -1 (-8175 1900)(-8225 1900);
WIRE 16 -1 (-8225 1900)(-8225 1800);
WIRE 16 -1 (-5900 900)(-5900 700);
WIRE 16 -1 (-8725 4900)(-8500 4900);
WIRE 16 -1 (-8725 4900)(-8725 4700);
WIRE 16 -1 (-7950 4900)(-7950 4750);
WIRE 16 -1 (-7950 4900)(-8300 4900);
WIRE 16 -1 (-6200 4700)(-6200 4550);
WIRE 16 -1 (-6200 5850)(-6200 5650);
WIRE 16 -1 (-5600 4700)(-5600 4550);
WIRE 16 -1 (-5600 5850)(-5600 5650);
WIRE 16 -1 (-1625 4825)(-1625 4950);
WIRE 16 -1 (-1625 5825)(-1625 5900);
WIRE 16 -1 (-8075 6100)(-8075 5975);
WIRE 16 -1 (-5450 2675)(-5475 2675);
WIRE 16 -1 (-5475 2675)(-5475 2550);
WIRE 16 -1 (-5500 3925)(-5500 3750);
WIRE 16 -1 (-4500 2800)(-4500 2925);
WIRE 16 -1 (-4500 3900)(-4500 3800);
WIRE 16 -1 (-4100 2800)(-4100 2925);
WIRE 16 -1 (-3675 2800)(-3675 2925);
WIRE 16 -1 (-3325 3050)(-3325 3175);
WIRE 16 -1 (-3075 3900)(-3075 3950);
WIRE 16 -1 (-8650 450)(-8650 375);
WIRE 16 -1 (-975 3975)(-975 3800);
WIRE 16 -1 (-5175 2225)(-5175 2050);
WIRE 16 -1 (-4175 1100)(-4175 1225);
WIRE 16 -1 (-4175 2200)(-4175 2100);
WIRE 16 -1 (-3775 1100)(-3775 1225);
WIRE 16 -1 (-2750 2200)(-2750 2250);
WIRE 16 -1 (-650 2275)(-650 2100);
WIRE 16 -1 (-5125 975)(-5150 975);
WIRE 16 -1 (-5150 975)(-5150 850);
WIRE 16 -1 (-3350 1100)(-3350 1225);
WIRE 16 -1 (-3000 1350)(-3000 1475);
WIRE 16 -1 (-4650 6125)(-4650 6025);
WIRE 16 2175 (-8550 1675)(-7325 1675);
WIRE 16 2175 (-8550 2575)(-8550 1675);
WIRE 16 2175 (-7325 2575)(-7325 1675);
WIRE 16 2175 (-8550 2575)(-7325 2575);
WIRE 16 -1 (-1525 1725)(-650 1725);
FORCEPROP 2 LAST SIG_NAME IRQ_UV_DETECT_N
J 0
(-1335 1735);
DISPLAY 0.723404 (-1335 1735);
WIRE 16 -1 (-650 1900)(-650 1725);
WIRE 16 -1 (-650 1725)(-550 1725);
WIRE 16 -1 (-5175 1275)(-5175 1675);
WIRE 16 -1 (-5175 1275)(-5125 1275);
WIRE 16 -1 (-5175 1675)(-3775 1675);
FORCEPROP 2 LAST SIG_NAME UV_P2V5_COMP
J 0
(-4035 1685);
DISPLAY 0.723404 (-4035 1685);
FORCEPROP 2 LASTPROP $XRERR UNIQUE?
J 0
(-4275 1685);
DISPLAY 0.638298 (-4275 1685);
PAINT MONO (-4275 1685);
DISPLAY INVISIBLE (-4275 1685);
WIRE 16 -1 (-5175 1850)(-5175 1675);
WIRE 16 -1 (-3775 1675)(-3250 1675);
WIRE 16 -1 (-3775 1425)(-3775 1675);
WIRE 16 -1 (-4175 1425)(-4175 1775);
WIRE 16 -1 (-4175 1775)(-3350 1775);
FORCEPROP 2 LAST SIG_NAME P12V_AUX_UV_TRIGGER
J 0
(-3960 1785);
DISPLAY 0.723404 (-3960 1785);
FORCEPROP 2 LASTPROP $XRERR UNIQUE?
J 0
(-4200 1785);
DISPLAY 0.638298 (-4200 1785);
PAINT MONO (-4200 1785);
DISPLAY INVISIBLE (-4200 1785);
WIRE 16 -1 (-4175 1775)(-4175 1900);
WIRE 16 -1 (-3350 1775)(-3300 1775);
WIRE 16 -1 (-3350 1425)(-3350 1775);
WIRE 16 -1 (-3300 1775)(-3300 2050);
WIRE 16 -1 (-3300 1775)(-3250 1775);
WIRE 16 -1 (-3300 2050)(-2650 2050);
WIRE 16 -1 (-1625 5250)(-1625 5475);
WIRE 16 -1 (-1625 5475)(-425 5475);
FORCEPROP 2 LAST SIG_NAME IRQ_UV_DETECT_N
J 0
(-1185 5485);
DISPLAY 0.723404 (-1185 5485);
WIRE 16 -1 (-1625 5475)(-1625 5625);
WIRE 16 -1 (-6200 4900)(-6200 5150);
WIRE 16 -1 (-4200 5150)(-6200 5150);
FORCEPROP 2 LAST SIG_NAME A_P12V_STBY_ADR_TRIGGER
J 0
(-5460 5160);
DISPLAY 0.723404 (-5460 5160);
FORCEPROP 2 LASTPROP $XRERR UNIQUE?
J 0
(-5700 5160);
DISPLAY 0.638298 (-5700 5160);
PAINT MONO (-5700 5160);
DISPLAY INVISIBLE (-5700 5160);
WIRE 16 -1 (-6200 5150)(-6200 5450);
WIRE 16 -1 (-5600 5450)(-5600 5050);
WIRE 16 -1 (-4200 5050)(-5600 5050);
FORCEPROP 2 LAST SIG_NAME A_P12V_STBY_FP_TRIGGER
J 0
(-5460 5060);
DISPLAY 0.723404 (-5460 5060);
FORCEPROP 2 LASTPROP $XRERR UNIQUE?
J 0
(-5700 5060);
DISPLAY 0.638298 (-5700 5060);
PAINT MONO (-5700 5060);
DISPLAY INVISIBLE (-5700 5060);
WIRE 16 -1 (-5600 4900)(-5600 5050);
WIRE 16 -1 (-2750 1725)(-1850 1725);
FORCEPROP 2 LAST SIG_NAME IRQ_UV_DETECT_R2_N
J 0
(-2685 1735);
DISPLAY 0.723404 (-2685 1735);
FORCEPROP 2 LASTPROP $XRERR UNIQUE?
J 0
(-2925 1735);
DISPLAY 0.638298 (-2925 1735);
PAINT MONO (-2925 1735);
DISPLAY INVISIBLE (-2925 1735);
WIRE 16 -1 (-1850 2050)(-1850 1725);
WIRE 16 -1 (-1725 1725)(-1850 1725);
WIRE 16 -1 (-2450 2050)(-1850 2050);
WIRE 16 -1 (-5500 2975)(-5500 3375);
WIRE 16 -1 (-5500 2975)(-5450 2975);
WIRE 16 -1 (-5500 3375)(-4100 3375);
FORCEPROP 2 LAST SIG_NAME UV_ADR_P2V5_COMP
J 0
(-4360 3385);
DISPLAY 0.723404 (-4360 3385);
FORCEPROP 2 LASTPROP $XRERR UNIQUE?
J 0
(-4600 3385);
DISPLAY 0.638298 (-4600 3385);
PAINT MONO (-4600 3385);
DISPLAY INVISIBLE (-4600 3385);
WIRE 16 -1 (-5500 3550)(-5500 3375);
WIRE 16 -1 (-4100 3375)(-3575 3375);
WIRE 16 -1 (-4100 3125)(-4100 3375);
WIRE 16 -1 (-4500 3125)(-4500 3475);
WIRE 16 -1 (-4500 3475)(-3675 3475);
FORCEPROP 2 LAST SIG_NAME P12V_AUX_UV_ADR_TRIGGER
J 0
(-4479 3475);
DISPLAY 0.723404 (-4479 3475);
FORCEPROP 2 LASTPROP $XRERR UNIQUE?
J 0
(-4719 3475);
DISPLAY 0.638298 (-4719 3475);
PAINT MONO (-4719 3475);
DISPLAY INVISIBLE (-4719 3475);
WIRE 16 -1 (-4500 3475)(-4500 3600);
WIRE 16 -1 (-3675 3475)(-3625 3475);
WIRE 16 -1 (-3675 3125)(-3675 3475);
WIRE 16 -1 (-3625 3475)(-3575 3475);
WIRE 16 -1 (-3625 3475)(-3625 3750);
WIRE 16 -1 (-3625 3750)(-2975 3750);
WIRE 16 2175 (-6325 4450)(-5400 4450);
WIRE 16 2175 (-6325 4600)(-6325 4450);
WIRE 16 2175 (-5400 4600)(-5400 4450);
WIRE 16 2175 (-6325 4600)(-5400 4600);
WIRE 16 -1 (-8075 5775)(-8075 5725);
WIRE 16 -1 (-8075 5650)(-8075 5725);
WIRE 16 -1 (-8075 5725)(-8575 5725);
WIRE 16 -1 (-8575 5650)(-8575 5725);
WIRE 16 -1 (-8575 5725)(-8800 5725);
FORCEPROP 2 LAST SIG_NAME P12V_PSU_FUSE
J 0
(-8610 5735);
DISPLAY 0.638298 (-8610 5735);
PAINT WHITE (-8610 5735);
WIRE 16 2175 (-8675 5675)(-7575 5675);
WIRE 16 2175 (-8675 6050)(-8675 5675);
WIRE 16 2175 (-7575 6050)(-7575 5675);
WIRE 16 2175 (-8675 6050)(-7575 6050);
WIRE 16 -1 (-6625 1725)(-7200 1725);
FORCEPROP 2 LAST SIG_NAME P12V_PSU_FUSE
J 0
(-7085 1735);
DISPLAY 0.638298 (-7085 1735);
PAINT WHITE (-7085 1735);
WIRE 16 -1 (-7200 1725)(-7200 1500);
WIRE 16 -1 (-7200 1500)(-6925 1500);
WIRE 16 -1 (-8000 1500)(-7200 1500);
WIRE 16 -1 (-8000 1200)(-8000 1500);
WIRE 16 -1 (-5900 1100)(-5900 1500);
WIRE 16 -1 (-5900 1500)(-5800 1500);
WIRE 16 -1 (-5900 1500)(-6525 1500);
FORCEPROP 2 LAST SIG_NAME HSC_EN
J 0
(-6010 1510);
DISPLAY 0.723404 (-6010 1510);
WIRE 16 -1 (-6525 1500)(-6525 1025);
WIRE 16 -1 (-6525 1500)(-6725 1500);
WIRE 16 -1 (-6525 1000)(-6525 1025);
WIRE 16 -1 (-7425 1025)(-6525 1025);
WIRE 16 -1 (-7425 975)(-7425 1025);
WIRE 16 -1 (-2975 5150)(-2150 5150);
FORCEPROP 2 LAST SIG_NAME FM_UV_ADR_TRIGGER_N
J 0
(-2910 5160);
DISPLAY 0.723404 (-2910 5160);
WIRE 16 -1 (-2975 5150)(-2975 5450);
WIRE 16 -1 (-2975 5150)(-3450 5150);
WIRE 16 -1 (-3275 5425)(-3275 5050);
WIRE 16 -1 (-1775 5050)(-3275 5050);
FORCEPROP 2 LAST SIG_NAME A_P12V_STBY_FPH_GATE
J 0
(-2935 5060);
DISPLAY 0.723404 (-2935 5060);
FORCEPROP 2 LASTPROP $XRERR UNIQUE?
J 0
(-3175 5060);
DISPLAY 0.638298 (-3175 5060);
PAINT MONO (-3175 5060);
DISPLAY INVISIBLE (-3175 5060);
WIRE 16 -1 (-3450 5050)(-3275 5050);
WIRE 16 -1 (-7650 3550)(-7075 3550);
FORCEPROP 2 LAST SIG_NAME SMB_SML1_PMBUS_HSC_R1_SDA
J 0
(-7610 3560);
DISPLAY 0.468085 (-7610 3560);
WIRE 16 -1 (-7075 3600)(-7650 3600);
FORCEPROP 2 LAST SIG_NAME SMB_SML1_PMBUS_HSC_R1_SCL
J 0
(-7610 3610);
DISPLAY 0.468085 (-7610 3610);
WIRE 16 -1 (-4400 5200)(-4400 5750);
WIRE 16 -1 (-4400 5200)(-4200 5200);
WIRE 16 -1 (-4400 5750)(-4650 5750);
WIRE 16 -1 (-4650 5825)(-4650 5750);
WIRE 16 -1 (-4650 5750)(-5050 5750);
FORCEPROP 2 LAST SIG_NAME U206_VS
J 0
(-5010 5760);
DISPLAY 0.680851 (-5010 5760);
FORCEPROP 2 LASTPROP $XRERR UNIQUE?
J 0
(-5250 5760);
DISPLAY 0.638298 (-5250 5760);
PAINT MONO (-5250 5760);
DISPLAY INVISIBLE (-5250 5760);
WIRE 16 -1 (-4650 5625)(-4650 5750);
WIRE 16 -1 (-5050 5650)(-5050 5750);
WIRE 16 -1 (-2775 3750)(-2250 3750);
WIRE 16 -1 (-2250 3750)(-2250 3425);
WIRE 16 -1 (-2050 3425)(-2250 3425);
WIRE 16 -1 (-3075 3425)(-2250 3425);
FORCEPROP 2 LAST SIG_NAME FM_UV_ADR_TRIGGER_N_R2
J 0
(-3010 3435);
DISPLAY 0.723404 (-3010 3435);
FORCEPROP 2 LASTPROP $XRERR UNIQUE?
J 0
(-3250 3435);
DISPLAY 0.638298 (-3250 3435);
PAINT MONO (-3250 3435);
DISPLAY INVISIBLE (-3250 3435);
WIRE 16 -1 (-1850 3425)(-975 3425);
FORCEPROP 2 LAST SIG_NAME FM_UV_ADR_TRIGGER_N
J 0
(-1660 3435);
DISPLAY 0.723404 (-1660 3435);
WIRE 16 -1 (-975 3600)(-975 3425);
WIRE 16 -1 (-975 3425)(-875 3425);
WIRE 16 -1 (-8175 1950)(-8325 1950);
WIRE 16 -1 (-8325 1950)(-8325 775);
WIRE 16 -1 (-8000 775)(-8325 775);
WIRE 16 -1 (-8325 775)(-8650 775);
WIRE 16 -1 (-8650 775)(-8650 650);
WIRE 16 -1 (-8775 775)(-8650 775);
FORCEPROP 2 LAST SIG_NAME PDB_PRSNT_R_N
J 0
(-8785 785);
DISPLAY 0.808511 (-8785 785);
PAINT WHITE (-8785 785);
WIRE 16 -1 (-8000 1000)(-8000 775);
WIRE 16 -1 (-8000 775)(-7950 775);
WIRE 16 -1 (-7625 775)(-7950 775);
WIRE 16 -1 (-7950 775)(-7950 700);
WIRE 16 -1 (-4650 5425)(-4650 5375);
WIRE 16 -1 (-4650 5375)(-5050 5375);
WIRE 16 -1 (-5050 5450)(-5050 5375);
WIRE 16 -1 (-5050 5375)(-5050 5350);
WIRE 16 -1 (-2750 2500)(-2750 2450);
WIRE 16 -1 (-3000 2500)(-2750 2500);
WIRE 16 -1 (-3000 1975)(-3000 2500);
WIRE 16 -1 (-3000 2500)(-3000 2525);
WIRE 16 -1 (-3075 4200)(-3075 4150);
WIRE 16 -1 (-3325 4200)(-3075 4200);
WIRE 16 -1 (-3325 3675)(-3325 4200);
WIRE 16 -1 (-3325 4200)(-3325 4225);
WIRE 16 -1 (-2975 5750)(-2975 5650);
WIRE 16 -1 (-3275 5750)(-2975 5750);
WIRE 16 -1 (-3275 5625)(-3275 5750);
WIRE 16 -1 (-3275 5750)(-3275 5850);
WIRE 16 -1 (-8075 5400)(-8075 5350);
WIRE 16 -1 (-7525 5350)(-8075 5350);
WIRE 16 -1 (-8575 5350)(-8075 5350);
WIRE 16 -1 (-8575 5400)(-8575 5350);
WIRE 16 -1 (-7525 5350)(-7525 5325);
WIRE 16 -1 (-3375 5000)(-3450 5000);
WIRE 16 -1 (-3375 4875)(-3375 5000);
WIRE 16 -1 (-7950 500)(-7950 400);
WIRE 16 -1 (-7950 400)(-7425 400);
WIRE 16 -1 (-7425 575)(-7425 400);
WIRE 16 -1 (-7425 400)(-7425 375);
DOT 1 (-8325 775);
DOT 1 (-8650 775);
DOT 1 (-3325 4200);
DOT 1 (-5500 3375);
DOT 1 (-8075 5725);
DOT 1 (-8075 5350);
DOT 1 (-8575 5725);
DOT 1 (-2975 5150);
DOT 1 (-6200 5150);
DOT 1 (-5900 1500);
DOT 1 (-6525 1500);
DOT 1 (-6525 1025);
DOT 1 (-7200 1500);
DOT 1 (-7425 400);
DOT 1 (-7950 775);
DOT 1 (-8000 775);
DOT 1 (-3625 3475);
DOT 1 (-5175 1675);
DOT 1 (-3775 1675);
DOT 1 (-3675 3475);
DOT 1 (-3350 1775);
DOT 1 (-1850 1725);
DOT 1 (-4175 1775);
DOT 1 (-3275 5050);
DOT 1 (-3275 5750);
DOT 1 (-4500 3475);
DOT 1 (-4100 3375);
DOT 1 (-2250 3425);
DOT 1 (-3300 1775);
DOT 1 (-3000 2500);
DOT 1 (-5600 5050);
DOT 1 (-1625 5475);
DOT 1 (-4650 5750);
DOT 1 (-5050 5375);
DOT 1 (-975 3425);
DOT 1 (-650 1725);
FORCENOTE
JUMPER 1-2
(-8050 2350) 0;
DISPLAY LEFT (-8050 2350);
DISPLAY 1.276596 (-8050 2350);
PAINT WHITE (-8050 2350);
FORCENOTE
NOTE:NEED TO SET UV VOL
(-6700 4275) 0;
DISPLAY LEFT (-6700 4275);
DISPLAY 1.595745 (-6700 4275);
PAINT WHITE (-6700 4275);
QUIT
